G04 ================== begin FILE IDENTIFICATION RECORD ==================*
G04 Layout Name:  D:/<user>/Wistron_project/16315-1/gbr/16315-1.brd*
G04 Film Name:    DP_REF_L1*
G04 File Format:  Gerber RS274X*
G04 File Origin:  Cadence Allegro 16.5-S056*
G04 Origin Date:  Fri Jun 09 15:32:23 2017*
G04 *
G04 Layer:  BOARD GEOMETRY/DP_REF_L1_TBL*
G04 Layer:  BOARD GEOMETRY/DP_REF_L1_TOP*
G04 Layer:  BOARD GEOMETRY/PANEL_OUTLINE*
G04 *
G04 Offset:    (0.00 0.00)*
G04 Mirror:    No*
G04 Mode:      Positive*
G04 Rotation:  0*
G04 FullContactRelief:  No*
G04 UndefLineWidth:     6.00*
G04 ================== end FILE IDENTIFICATION RECORD ====================*
%FSLAX35Y35*MOIN*%
%IR0*IPPOS*OFA0.00000B0.00000*MIA0B0*SFA1.00000B1.00000*%
%ADD10C,.02*%
%ADD11C,.005*%
%ADD12C,.006*%
%ADD13C,.0065*%
G75*
%LPD*%
G75*
G54D10*
G01X1985143Y1554618D02*
X2720143D01*
G01X1985143Y1519968D02*
X2720143D01*
G01X1985143Y1623918D02*
Y1519968D01*
G01Y1589268D02*
X2720143D01*
G01X1985143Y1623918D02*
X2720143D01*
G01X2160143D02*
Y1519968D01*
G01X2405143Y1623918D02*
Y1519968D01*
G01X2510143Y1623918D02*
Y1519968D01*
G01X2720143Y1623918D02*
Y1519968D01*
G54D11*
G01X140144Y182472D02*
X164925Y249648D01*
G01X139117Y183012D02*
X163907Y250212D01*
G01X133846Y173544D02*
X140144Y182472D01*
G01X133038Y174394D02*
X139117Y183012D01*
G01X132245Y172531D02*
X133846Y173544D01*
G01X131911Y173681D02*
X133038Y174394D01*
G01X131124Y173681D02*
X131911D01*
G01X131352Y172531D02*
X132245D01*
G01X131124Y173681D02*
X131911D01*
G01X139117Y183012D02*
X163907Y250212D01*
G01X140144Y182472D02*
X164925Y249648D01*
G01X133038Y174394D02*
X139117Y183012D01*
G01X133846Y173544D02*
X140144Y182472D01*
G01X131911Y173681D02*
X133038Y174394D01*
G01X132245Y172531D02*
X133846Y173544D01*
G01X131124Y173681D02*
X131911D01*
G01X132245Y172531D02*
X133846Y173544D01*
G01X131352Y172531D02*
X132245D01*
G01X127488Y188567D02*
X124463D01*
G01X127488Y187417D02*
X124463D01*
G01X127488D02*
X124463D01*
G01X127488Y188567D02*
X124463D01*
G01X124880Y172417D02*
X124463D01*
G01X124880Y173567D02*
X124463D01*
G01X124880D02*
X124463D01*
G01X124880Y172417D02*
X124463D01*
G01X164925Y249648D02*
X232721Y337136D01*
G01X163907Y250212D02*
X231934Y337999D01*
G01X163907Y250212D02*
X231934Y337999D01*
G01X164925Y249648D02*
X232721Y337136D01*
G01X146856Y641433D02*
X160150Y701401D01*
G01X145777Y641880D02*
X159129Y702113D01*
G01X137982Y627504D02*
X146856Y641433D01*
G01X137149Y628337D02*
X145777Y641880D01*
G01X135213Y625740D02*
X137982Y627504D01*
G01X134766Y626819D02*
X137149Y628337D01*
G01X133476Y625355D02*
X135213Y625740D01*
G01X133350Y626505D02*
X134766Y626819D01*
G01X131620Y625355D02*
X133476D01*
G01X131256Y626505D02*
X133350D01*
G01X145777Y641880D02*
X159129Y702113D01*
G01X146856Y641433D02*
X160150Y701401D01*
G01X137149Y628337D02*
X145777Y641880D01*
G01X137982Y627504D02*
X146856Y641433D01*
G01X134766Y626819D02*
X137149Y628337D01*
G01X135213Y625740D02*
X137982Y627504D01*
G01X133350Y626505D02*
X134766Y626819D01*
G01X133476Y625355D02*
X135213Y625740D01*
G01X131256Y626505D02*
X133350D01*
G01X131620Y625355D02*
X133476D01*
G01X127488Y641323D02*
X124463D01*
G01X127488Y640173D02*
X124463D01*
G01X127488D02*
X124463D01*
G01X127488Y641323D02*
X124463D01*
G01X124880Y625173D02*
X124463D01*
G01X124880Y626323D02*
X124463D01*
G01X124880D02*
X124463D01*
G01X124880Y625173D02*
X124463D01*
G01X160151Y701401D02*
X214429Y786609D01*
G01X159316Y702233D02*
X213596Y787442D01*
G01X159316Y702233D02*
X213596Y787442D01*
G01X160151Y701401D02*
X214429Y786609D01*
G01X138718Y1081098D02*
X170418Y1167060D01*
G01X137773Y1081862D02*
X169383Y1167579D01*
G01X133907Y1078052D02*
X138718Y1081098D01*
G01X133573Y1079202D02*
X137773Y1081862D01*
G01X131161Y1078052D02*
X133907D01*
G01X130915Y1079202D02*
X133573D01*
G01X137773Y1081862D02*
X169383Y1167579D01*
G01X138718Y1081098D02*
X170418Y1167060D01*
G01X133573Y1079202D02*
X137773Y1081862D01*
G01X133907Y1078052D02*
X138718Y1081098D01*
G01X130915Y1079202D02*
X133573D01*
G01X131161Y1078052D02*
X133907D01*
G01X124880Y1077929D02*
X124463D01*
G01X124880Y1079079D02*
X124463D01*
G01X124880D02*
X124463D01*
G01X124880Y1077929D02*
X124463D01*
G01X127488Y1094079D02*
X124463D01*
G01X127488Y1092929D02*
X124463D01*
G01X127488D02*
X124463D01*
G01X127488Y1094079D02*
X124463D01*
G01X214429Y786609D02*
X373454Y888030D01*
G01X213596Y787442D02*
X293324Y838290D01*
G01X214429Y786609D02*
X373454Y888030D01*
G01X213596Y787442D02*
X293324Y838290D01*
G01X214429Y786609D02*
X373454Y888030D01*
G01X172856Y1170814D02*
X197086Y1208125D01*
G01X171891Y1171441D02*
X196121Y1208752D01*
G01X170418Y1167060D02*
X172856Y1170814D01*
G01X169383Y1167579D02*
X171891Y1171441D01*
G01D02*
X196121Y1208752D01*
G01X172856Y1170814D02*
X197086Y1208125D01*
G01X169383Y1167579D02*
X171891Y1171441D01*
G01X170418Y1167060D02*
X172856Y1170814D01*
G01X197086Y1208125D02*
X223755Y1249191D01*
G01X196121Y1208752D02*
X222933Y1250039D01*
G01X196121Y1208752D02*
X222933Y1250039D01*
G01X197086Y1208125D02*
X223755Y1249191D01*
G01X257428Y172508D02*
X255541D01*
G01X257094Y173658D02*
X255359D01*
G01X261329Y174978D02*
X257428Y172508D01*
G01X260384Y175742D02*
X257094Y173658D01*
G01X289185Y250545D02*
X261329Y174978D01*
G01X288150Y251063D02*
X260384Y175742D01*
G01X257094Y173658D02*
X255359D01*
G01X257428Y172508D02*
X255541D01*
G01X260384Y175742D02*
X257094Y173658D01*
G01X261329Y174978D02*
X257428Y172508D01*
G01X288150Y251063D02*
X260384Y175742D01*
G01X289185Y250545D02*
X261329Y174978D01*
G01X251700Y188567D02*
X248813D01*
G01X251700Y187417D02*
X248675D01*
G01X251700D02*
X248675D01*
G01X251700Y188567D02*
X248813D01*
G01X249092Y172417D02*
X248675D01*
G01X249092Y173567D02*
X248675D01*
G01X249092D02*
X248675D01*
G01X249092Y172417D02*
X248675D01*
G01X231934Y337999D02*
X357142Y417764D01*
G01X231934Y337999D02*
X357142Y417764D01*
G01X231934Y337999D02*
X357142Y417764D01*
G01X232721Y337136D02*
X266474Y358639D01*
G01X231934Y337999D02*
X357142Y417764D01*
G01X231934Y337999D02*
X357142Y417764D01*
G01X232721Y337136D02*
X266474Y358639D01*
G01X263665Y628407D02*
X268915Y636644D01*
G01X262832Y629240D02*
X267836Y637091D01*
G01X259197Y625560D02*
X263665Y628407D01*
G01X258750Y626639D02*
X262832Y629240D01*
G01X258181Y625335D02*
X259197Y625560D01*
G01X258055Y626485D02*
X258750Y626639D01*
G01X256212Y625335D02*
X258181D01*
G01X255888Y626485D02*
X258055D01*
G01X262832Y629240D02*
X267836Y637091D01*
G01X263665Y628407D02*
X268915Y636644D01*
G01X258750Y626639D02*
X262832Y629240D01*
G01X259197Y625560D02*
X263665Y628407D01*
G01X258055Y626485D02*
X258750Y626639D01*
G01X258181Y625335D02*
X259197Y625560D01*
G01X255888Y626485D02*
X258055D01*
G01X256212Y625335D02*
X258181D01*
G01X251700Y641323D02*
X248675D01*
G01X251700Y640173D02*
X248675D01*
G01X251700D02*
X248675D01*
G01X251700Y641323D02*
X248675D01*
G01X249092Y625173D02*
X248675D01*
G01X249092Y626323D02*
X248675D01*
G01X249092D02*
X248675D01*
G01X249092Y625173D02*
X248675D01*
G01X262408Y1080978D02*
X349878Y1318182D01*
G01X261463Y1081742D02*
X283271Y1140879D01*
G01X257802Y1078061D02*
X262408Y1080978D01*
G01X257468Y1079211D02*
X261463Y1081742D01*
G01X255982Y1078061D02*
X257802D01*
G01X255718Y1079211D02*
X257468D01*
G01X262408Y1080978D02*
X349878Y1318182D01*
G01X261463Y1081742D02*
X283271Y1140879D01*
G01X262408Y1080978D02*
X349878Y1318182D01*
G01X257468Y1079211D02*
X261463Y1081742D01*
G01X257802Y1078061D02*
X262408Y1080978D01*
G01X255718Y1079211D02*
X257468D01*
G01X255982Y1078061D02*
X257802D01*
G01X249092Y1077929D02*
X248675D01*
G01X249092Y1079079D02*
X248675D01*
G01X249092D02*
X248675D01*
G01X249092Y1077929D02*
X248675D01*
G01X251700Y1094079D02*
X248675D01*
G01X251700Y1092929D02*
X248675D01*
G01X251700D02*
X248675D01*
G01X251700Y1094079D02*
X248675D01*
G01X223757Y1249193D02*
X368367Y1337218D01*
G01X223041Y1250104D02*
X367942Y1338306D01*
G01X223041Y1250104D02*
X367942Y1338306D01*
G01X223757Y1249193D02*
X368367Y1337218D01*
G01X327842Y310072D02*
X289185Y250545D01*
G01X327001Y310890D02*
X288150Y251063D01*
G01X327001Y310890D02*
X288150Y251063D01*
G01X327842Y310072D02*
X289185Y250545D01*
G01X300229Y380143D02*
X326500Y396879D01*
G01X266474Y358639D02*
X300229Y380143D01*
G01D02*
X326500Y396879D01*
G01X266474Y358639D02*
X300229Y380143D01*
G01X268915Y636644D02*
X285176Y710012D01*
G01X267836Y637091D02*
X284076Y710367D01*
G01X267836Y637091D02*
X284076Y710367D01*
G01X268915Y636644D02*
X285176Y710012D01*
G01X285180Y710023D02*
X342533Y850692D01*
G01X284078Y710367D02*
X311479Y777574D01*
G01X285180Y710023D02*
X342533Y850692D01*
G01X285180Y710023D02*
X342533Y850692D01*
G01X284078Y710367D02*
X311479Y777574D01*
G01X285180Y710023D02*
X342533Y850692D01*
G01X311479Y777574D02*
X318320Y794352D01*
G01X311479Y777574D02*
X318320Y794352D01*
G01X293324Y838290D02*
X373017Y889116D01*
G01X293324Y838290D02*
X373017Y889116D01*
G01X283271Y1140879D02*
X348934Y1318946D01*
G01X283271Y1140879D02*
X348934Y1318946D01*
G01X346703Y323074D02*
X327842Y310072D01*
G01X346236Y324150D02*
X327001Y310890D01*
G01X464699Y348896D02*
X346703Y323074D01*
G01X464236Y349973D02*
X346236Y324150D01*
G01D02*
X327001Y310890D01*
G01X346703Y323074D02*
X327842Y310072D01*
G01X464236Y349973D02*
X346236Y324150D01*
G01X464699Y348896D02*
X346703Y323074D01*
G01X326500Y396879D02*
X357760Y416794D01*
G01X326500Y396879D02*
X357760Y416794D01*
G01D02*
X372158Y425968D01*
G01X357142Y417764D02*
X371698Y427039D01*
G01X357142Y417764D02*
X371698Y427039D01*
G01X357760Y416794D02*
X372158Y425968D01*
G01X318320Y794352D02*
X341507Y851222D01*
G01X318320Y794352D02*
X341507Y851222D01*
G01X351398Y864605D02*
X376161Y879773D01*
G01X350570Y865448D02*
X375734Y880861D01*
G01X342533Y850692D02*
X351398Y864605D01*
G01X341507Y851222D02*
X350570Y865448D01*
G01D02*
X375734Y880861D01*
G01X351398Y864605D02*
X376161Y879773D01*
G01X341507Y851222D02*
X350570Y865448D01*
G01X342533Y850692D02*
X351398Y864605D01*
G01X349878Y1318182D02*
X370163Y1331015D01*
G01X348934Y1318946D02*
X369728Y1332101D01*
G01X348934Y1318946D02*
X369728Y1332101D01*
G01X349878Y1318182D02*
X370163Y1331015D01*
G01X381047Y172561D02*
X379807D01*
G01X380713Y173711D02*
X379519D01*
G01X386711Y176146D02*
X381047Y172561D01*
G01X380713Y173711D02*
X379519D01*
G01X385766Y176910D02*
X380713Y173711D01*
G01X416373Y256612D02*
X386711Y176146D01*
G01X415338Y257130D02*
X385766Y176910D01*
G01X380713Y173711D02*
X379519D01*
G01X381047Y172561D02*
X379807D01*
G01X386711Y176146D02*
X381047Y172561D01*
G01X385766Y176910D02*
X380713Y173711D01*
G01X386711Y176146D02*
X381047Y172561D01*
G01X415338Y257130D02*
X385766Y176910D01*
G01X416373Y256612D02*
X386711Y176146D01*
G01X375913Y188567D02*
X372888D01*
G01X375913Y187417D02*
X372888D01*
G01X375913D02*
X372888D01*
G01X375913Y188567D02*
X372888D01*
G01X373305Y172417D02*
X372888D01*
G01X373305Y173567D02*
X372888D01*
G01X373305D02*
X372888D01*
G01X373305Y172417D02*
X372888D01*
G01X372158Y425968D02*
X658658Y497107D01*
G01X371698Y427039D02*
X658122Y498160D01*
G01X371698Y427039D02*
X658122Y498160D01*
G01X372158Y425968D02*
X658658Y497107D01*
G01X381731Y625299D02*
X379453D01*
G01X381604Y626449D02*
X379437D01*
G01X383632Y625721D02*
X381731Y625299D01*
G01X382023Y626543D02*
X381604Y626449D01*
G01X383976Y626976D02*
X382023Y626543D01*
G01X384423Y625897D02*
X383632Y625721D01*
G01X383976Y626976D02*
X382023Y626543D01*
G01X388405Y628432D02*
X384423Y625897D01*
G01X387572Y629266D02*
X383976Y626976D01*
G01X391263Y632912D02*
X388405Y628432D01*
G01X390184Y633359D02*
X387572Y629266D01*
G01X402741Y684734D02*
X391263Y632912D01*
G01X401817Y685884D02*
X390184Y633359D01*
G01X381604Y626449D02*
X379437D01*
G01X381731Y625299D02*
X379453D01*
G01X382023Y626543D02*
X381604Y626449D01*
G01X383632Y625721D02*
X381731Y625299D01*
G01X383976Y626976D02*
X382023Y626543D01*
G01X383632Y625721D02*
X381731Y625299D01*
G01X384423Y625897D02*
X383632Y625721D01*
G01X387572Y629266D02*
X383976Y626976D01*
G01X388405Y628432D02*
X384423Y625897D01*
G01X390184Y633359D02*
X387572Y629266D01*
G01X391263Y632912D02*
X388405Y628432D01*
G01X401817Y685884D02*
X390184Y633359D01*
G01X402741Y684734D02*
X391263Y632912D01*
G01X372888Y641323D02*
X375913D01*
G01Y640173D02*
X372888D01*
G01X375913D02*
X372888D01*
G01Y641323D02*
X375913D01*
G01X373305Y625173D02*
X372888D01*
G01X373305Y626323D02*
X372888D01*
G01X373305D02*
X372888D01*
G01X373305Y625173D02*
X372888D01*
G01X426048Y789957D02*
X402742Y684734D01*
G01X424925Y790206D02*
X401818Y685884D01*
G01X424925Y790206D02*
X401818Y685884D01*
G01X426048Y789957D02*
X402742Y684734D01*
G01X376161Y879773D02*
X560123Y916598D01*
G01X375734Y880861D02*
X559719Y917691D01*
G01X375734Y880861D02*
X559719Y917691D01*
G01X376161Y879773D02*
X560123Y916598D01*
G01X373454Y888030D02*
X558586Y925083D01*
G01X373017Y889116D02*
X558182Y926175D01*
G01X373017Y889116D02*
X558182Y926175D01*
G01X373454Y888030D02*
X558586Y925083D01*
G01X383164Y1079220D02*
X400335Y1125768D01*
G01X382219Y1079983D02*
X399142Y1125859D01*
G01X381395Y1078097D02*
X383164Y1079220D01*
G01X381060Y1079247D02*
X382219Y1079983D01*
G01X379931Y1078097D02*
X381395D01*
G01X379595Y1079247D02*
X381060D01*
G01X382219Y1079983D02*
X399142Y1125859D01*
G01X383164Y1079220D02*
X400335Y1125768D01*
G01X381060Y1079247D02*
X382219Y1079983D01*
G01X381395Y1078097D02*
X383164Y1079220D01*
G01X379595Y1079247D02*
X381060D01*
G01X379931Y1078097D02*
X381395D01*
G01X373305Y1077929D02*
X372888D01*
G01X373305Y1079079D02*
X372888D01*
G01X373305D02*
X372888D01*
G01X373305Y1077929D02*
X372888D01*
G01Y1094079D02*
X375913D01*
G01Y1092929D02*
X372888D01*
G01X375913D02*
X372888D01*
G01Y1094079D02*
X375913D01*
G01X399142Y1125859D02*
X395638Y1143090D01*
G01X400335Y1125768D02*
X398587Y1134363D01*
G01X399142Y1125859D02*
X395638Y1143090D01*
G01X399142Y1125859D02*
X395638Y1143090D01*
G01X400335Y1125768D02*
X398587Y1134363D01*
G01X396838Y1142961D02*
X417690Y1190394D01*
G01X395638Y1143090D02*
X416637Y1190857D01*
G01X398587Y1134364D02*
X396838Y1142961D01*
G01X395638Y1143090D02*
X416637Y1190857D01*
G01X396838Y1142961D02*
X417690Y1190394D01*
G01X398587Y1134364D02*
X396838Y1142961D01*
G01X370163Y1331015D02*
X442865Y1345567D01*
G01X369728Y1332101D02*
X442865Y1346740D01*
G01X369728Y1332101D02*
X442865Y1346740D01*
G01X370163Y1331015D02*
X442865Y1345567D01*
G01X368367Y1337218D02*
X442840Y1352125D01*
G01X367942Y1338306D02*
X442841Y1353299D01*
G01X367942Y1338306D02*
X442841Y1353299D01*
G01X368367Y1337218D02*
X442840Y1352125D01*
G01X423729Y267940D02*
X416373Y256612D01*
G01X422579Y268281D02*
X415338Y257130D01*
G01X422579Y268281D02*
X415338Y257130D01*
G01X423729Y267940D02*
X416373Y256612D01*
G01X451793Y311160D02*
X423729Y267941D01*
G01X450828Y311787D02*
X422579Y268282D01*
G01X450828Y311787D02*
X422579Y268282D01*
G01X451793Y311160D02*
X423729Y267941D01*
G01X462414Y327516D02*
X451793Y311160D01*
G01X456138Y319963D02*
X450828Y311787D01*
G01X461449Y328143D02*
X456138Y319963D01*
G01D02*
X450828Y311787D01*
G01X462414Y327516D02*
X451793Y311160D01*
G01X461449Y328143D02*
X456138Y319963D01*
G01X462414Y327516D02*
X451793Y311160D01*
G01X437589Y842054D02*
X426048Y789957D01*
G01X436495Y842438D02*
X424925Y790206D01*
G01X436495Y842438D02*
X424925Y790206D01*
G01X437589Y842054D02*
X426048Y789957D01*
G01X455681Y878858D02*
X437589Y842054D01*
G01X454778Y879628D02*
X436495Y842438D01*
G01X473794Y891669D02*
X455681Y878858D01*
G01X473322Y892745D02*
X454778Y879628D01*
G01D02*
X436495Y842438D01*
G01X455681Y878858D02*
X437589Y842054D01*
G01X473322Y892745D02*
X454778Y879628D01*
G01X473794Y891669D02*
X455681Y878858D01*
G01X418713Y1192722D02*
X595609Y1330338D01*
G01X417777Y1193451D02*
X595117Y1331413D01*
G01X417690Y1190394D02*
X418713Y1192722D01*
G01X416637Y1190857D02*
X417777Y1193451D01*
G01D02*
X595117Y1331413D01*
G01X418713Y1192722D02*
X595609Y1330338D01*
G01X416637Y1190857D02*
X417777Y1193451D01*
G01X417690Y1190394D02*
X418713Y1192722D01*
G01X442865Y1345567D02*
X540283Y1326083D01*
G01X442865Y1346740D02*
X540283Y1327256D01*
G01X442865Y1346740D02*
X540283Y1327256D01*
G01X442865Y1345567D02*
X540283Y1326083D01*
G01X442840Y1352125D02*
X539124Y1332607D01*
G01X442841Y1353299D02*
X539125Y1333781D01*
G01X442841Y1353299D02*
X539125Y1333781D01*
G01X442840Y1352125D02*
X539124Y1332607D01*
G01X506973Y172543D02*
X503821D01*
G01X506639Y173693D02*
X503849D01*
G01X510702Y174904D02*
X506973Y172543D01*
G01X509757Y175668D02*
X506639Y173693D01*
G01D02*
X503849D01*
G01X506973Y172543D02*
X503821D01*
G01X509757Y175668D02*
X506639Y173693D01*
G01X510702Y174904D02*
X506973Y172543D01*
G01X500125Y188567D02*
X497100D01*
G01X500125Y187417D02*
X497100D01*
G01X500125D02*
X497100D01*
G01X500125Y188567D02*
X497100D01*
G01X497517Y172417D02*
X497100D01*
G01X497517Y173567D02*
X497100D01*
G01X497517D02*
X497100D01*
G01X497517Y172417D02*
X497100D01*
G01X467724Y335694D02*
X462414Y327516D01*
G01X472196Y344692D02*
X461449Y328143D01*
G01X473036Y343873D02*
X467724Y335694D01*
G01X472196Y344692D02*
X461449Y328143D01*
G01X766299Y545036D02*
X473036Y343873D01*
G01X765441Y545843D02*
X472196Y344692D01*
G01D02*
X461449Y328143D01*
G01X467724Y335694D02*
X462414Y327516D01*
G01X473036Y343873D02*
X467724Y335694D01*
G01X765441Y545843D02*
X472196Y344692D01*
G01X766299Y545036D02*
X473036Y343873D01*
G01X550982Y407414D02*
X464699Y348896D01*
G01X550336Y408367D02*
X464236Y349973D01*
G01X550336Y408367D02*
X464236Y349973D01*
G01X550982Y407414D02*
X464699Y348896D01*
G01X507441Y625803D02*
X511690Y628511D01*
G01X506994Y626882D02*
X510857Y629344D01*
G01X505324Y625333D02*
X507441Y625803D01*
G01X505197Y626483D02*
X506994Y626882D01*
G01X503549Y625333D02*
X505324D01*
G01X503363Y626483D02*
X505197D01*
G01X506994Y626882D02*
X510857Y629344D01*
G01X507441Y625803D02*
X511690Y628511D01*
G01X505197Y626483D02*
X506994Y626882D01*
G01X505324Y625333D02*
X507441Y625803D01*
G01X503363Y626483D02*
X505197D01*
G01X503549Y625333D02*
X505324D01*
G01X500125Y641323D02*
X497100D01*
G01X500125Y640173D02*
X497100D01*
G01X500125D02*
X497100D01*
G01X500125Y641323D02*
X497100D01*
G01X497517Y625173D02*
X497100D01*
G01X497517Y626323D02*
X497100D01*
G01X497517D02*
X497100D01*
G01X497517Y625173D02*
X497100D01*
G01X486618Y894405D02*
X473794Y891669D01*
G01X479965Y894162D02*
X473322Y892745D01*
G01X486378Y895530D02*
X479965Y894162D01*
G01X488754Y894861D02*
X486618Y894405D01*
G01X488514Y895986D02*
X486378Y895530D01*
G01X542179Y906258D02*
X488754Y894861D01*
G01X490651Y896442D02*
X488514Y895986D01*
G01X541939Y907383D02*
X490651Y896442D01*
G01X479965Y894162D02*
X473322Y892745D01*
G01X486618Y894405D02*
X473794Y891669D01*
G01X486378Y895530D02*
X479965Y894162D01*
G01X486618Y894405D02*
X473794Y891669D01*
G01X488514Y895986D02*
X486378Y895530D01*
G01X488754Y894861D02*
X486618Y894405D01*
G01X490651Y896442D02*
X488514Y895986D01*
G01X542179Y906258D02*
X488754Y894861D01*
G01X541939Y907383D02*
X490651Y896442D01*
G01X542179Y906258D02*
X488754Y894861D01*
G01X505355Y1078115D02*
X534263Y1096552D01*
G01X505019Y1079265D02*
X533430Y1097385D01*
G01X503789Y1079265D02*
X505019D01*
G01X504161Y1078115D02*
X505355D01*
G01X503789Y1079265D02*
X505019D01*
G01D02*
X533430Y1097385D01*
G01X505355Y1078115D02*
X534263Y1096552D01*
G01X503789Y1079265D02*
X505019D01*
G01X505355Y1078115D02*
X534263Y1096552D01*
G01X504161Y1078115D02*
X505355D01*
G01X497517Y1077929D02*
X497100D01*
G01X497517Y1079079D02*
X497100D01*
G01X497517D02*
X497100D01*
G01X497517Y1077929D02*
X497100D01*
G01X500125Y1094079D02*
X497226D01*
G01X500125Y1092929D02*
X497100D01*
G01X500125D02*
X497100D01*
G01X500125Y1094079D02*
X497226D01*
G01X596118Y406548D02*
X510702Y174904D01*
G01X595085Y407073D02*
X509757Y175668D01*
G01X595085Y407073D02*
X509757Y175668D01*
G01X596118Y406548D02*
X510702Y174904D01*
G01X582221Y428600D02*
X550982Y407415D01*
G01X558146Y413663D02*
X550336Y408367D01*
G01X558146Y413663D02*
X550336Y408367D01*
G01X582221Y428600D02*
X550982Y407415D01*
G01X582221Y428600D02*
X550982Y407415D01*
G01X520047Y641629D02*
X550547Y779207D01*
G01X518968Y642076D02*
X549468Y779654D01*
G01X511690Y628511D02*
X520047Y641629D01*
G01X510857Y629344D02*
X518968Y642076D01*
G01D02*
X549468Y779654D01*
G01X520047Y641629D02*
X550547Y779207D01*
G01X510857Y629344D02*
X518968Y642076D01*
G01X511690Y628511D02*
X520047Y641629D01*
G01X550547Y779207D02*
X664349Y957849D01*
G01X549468Y779654D02*
X663533Y958710D01*
G01X549468Y779654D02*
X663533Y958710D01*
G01X550547Y779207D02*
X664349Y957849D01*
G01X569142Y912015D02*
X542179Y906258D01*
G01X568731Y913104D02*
X541939Y907383D01*
G01X568731Y913104D02*
X541939Y907383D01*
G01X569142Y912015D02*
X542179Y906258D01*
G01X541181Y1115522D02*
X537452Y1132349D01*
G01X540003Y1115522D02*
X536274Y1132349D01*
G01X538416Y1103062D02*
X541181Y1115522D01*
G01X537337Y1103509D02*
X540003Y1115522D01*
G01X534263Y1096552D02*
X538416Y1103062D01*
G01X533430Y1097385D02*
X537337Y1103509D01*
G01X540003Y1115522D02*
X536274Y1132349D01*
G01X541181Y1115522D02*
X537452Y1132349D01*
G01X537337Y1103509D02*
X540003Y1115522D01*
G01X538416Y1103062D02*
X541181Y1115522D01*
G01X533430Y1097385D02*
X537337Y1103509D01*
G01X534263Y1096552D02*
X538416Y1103062D01*
G01X537784Y1158686D02*
X545554Y1193739D01*
G01X536606Y1158686D02*
X544376Y1193740D01*
G01X540538Y1146267D02*
X537784Y1158686D01*
G01X539360Y1146267D02*
X536606Y1158686D01*
G01X537452Y1132349D02*
X540538Y1146267D01*
G01X536274Y1132349D02*
X539360Y1146267D01*
G01X536606Y1158686D02*
X544376Y1193740D01*
G01X537784Y1158686D02*
X545554Y1193739D01*
G01X539360Y1146267D02*
X536606Y1158686D01*
G01X540538Y1146267D02*
X537784Y1158686D01*
G01X536274Y1132349D02*
X539360Y1146267D01*
G01X537452Y1132349D02*
X540538Y1146267D01*
G01X545554Y1193741D02*
X578203Y1244993D01*
G01X544328Y1193958D02*
X577124Y1245442D01*
G01X544328Y1193958D02*
X577124Y1245442D01*
G01X545554Y1193741D02*
X578203Y1244993D01*
G01X540283Y1326083D02*
X624308Y1342913D01*
G01X540283Y1327256D02*
X624309Y1344087D01*
G01X540283Y1327256D02*
X624309Y1344087D01*
G01X540283Y1326083D02*
X624308Y1342913D01*
G01X539124Y1332607D02*
X623569Y1349509D01*
G01X539125Y1333781D02*
X623570Y1350683D01*
G01X539125Y1333781D02*
X623570Y1350683D01*
G01X539124Y1332607D02*
X623569Y1349509D01*
G01X602856Y416693D02*
X596118Y406548D01*
G01X597301Y410409D02*
X595085Y407073D01*
G01X600876Y415792D02*
X597301Y410409D01*
G01X604693Y419459D02*
X602856Y416693D01*
G01X603020Y419021D02*
X600875Y415792D01*
G01X603734Y420096D02*
X603021Y419022D01*
G01X606716Y424584D02*
X603734Y420096D01*
G01X597301Y410409D02*
X595085Y407073D01*
G01X602856Y416693D02*
X596118Y406548D01*
G01X600876Y415792D02*
X597301Y410409D01*
G01X602856Y416693D02*
X596118Y406548D01*
G01X603020Y419021D02*
X600875Y415792D01*
G01X604693Y419459D02*
X602856Y416693D01*
G01X603734Y420096D02*
X603021Y419022D01*
G01X604693Y419459D02*
X602856Y416693D01*
G01X606716Y424584D02*
X603734Y420096D01*
G01X581575Y429553D02*
X558146Y413663D01*
G01X721363Y522966D02*
X582221Y428600D01*
G01X720716Y523918D02*
X581575Y429553D01*
G01D02*
X558146Y413663D01*
G01X720716Y523918D02*
X581575Y429553D01*
G01X721363Y522966D02*
X582221Y428600D01*
G01X571056Y913090D02*
X569142Y912015D01*
G01X569169Y913350D02*
X568731Y913104D01*
G01X767435Y1024920D02*
X569168Y913351D01*
G01X753004Y1015479D02*
X571054Y913092D01*
G01X767435Y1024920D02*
X569168Y913351D01*
G01X767435Y1024920D02*
X569168Y913351D01*
G01X569169Y913350D02*
X568731Y913104D01*
G01X571056Y913090D02*
X569142Y912015D01*
G01X767435Y1024920D02*
X569168Y913351D01*
G01X571056Y913090D02*
X569142Y912015D01*
G01X753004Y1015479D02*
X571054Y913092D01*
G01X560123Y916596D02*
X766334Y1032652D01*
G01X559719Y917689D02*
X765517Y1033512D01*
G01X559719Y917689D02*
X765517Y1033512D01*
G01X560123Y916596D02*
X766334Y1032652D01*
G01X558586Y925083D02*
X583337Y938972D01*
G01X558182Y926175D02*
X582774Y939975D01*
G01X558182Y926175D02*
X582774Y939975D01*
G01X558586Y925083D02*
X583337Y938972D01*
G01D02*
X607931Y952774D01*
G01X582774Y939975D02*
X607368Y953777D01*
G01X582774Y939975D02*
X607368Y953777D01*
G01X583337Y938972D02*
X607931Y952774D01*
G01X578203Y1244993D02*
X591630Y1305548D01*
G01X577124Y1245442D02*
X590551Y1305995D01*
G01X577124Y1245442D02*
X590551Y1305995D01*
G01X578203Y1244993D02*
X591630Y1305548D01*
G01X601234Y1320625D02*
X612088Y1327241D01*
G01X600407Y1321468D02*
X611663Y1328329D01*
G01X591630Y1305548D02*
X601234Y1320625D01*
G01X590551Y1305995D02*
X600407Y1321468D01*
G01D02*
X611663Y1328329D01*
G01X601234Y1320625D02*
X612088Y1327241D01*
G01X590551Y1305995D02*
X600407Y1321468D01*
G01X591630Y1305548D02*
X601234Y1320625D01*
G01X595609Y1330338D02*
X625848Y1336390D01*
G01X595117Y1331413D02*
X625849Y1337564D01*
G01X595117Y1331413D02*
X625849Y1337564D01*
G01X595609Y1330338D02*
X625848Y1336390D01*
G01X630049Y172498D02*
X627969D01*
G01X629715Y173648D02*
X627807D01*
G01X636832Y176793D02*
X630049Y172498D01*
G01X635887Y177557D02*
X629715Y173648D01*
G01X756984Y502633D02*
X636832Y176793D01*
G01X755939Y503126D02*
X635887Y177557D01*
G01X629715Y173648D02*
X627807D01*
G01X630049Y172498D02*
X627969D01*
G01X635887Y177557D02*
X629715Y173648D01*
G01X636832Y176793D02*
X630049Y172498D01*
G01X755939Y503126D02*
X635887Y177557D01*
G01X756984Y502633D02*
X636832Y176793D01*
G01X624338Y188567D02*
X621383D01*
G01X624338Y187417D02*
X621313D01*
G01X624338D02*
X621313D01*
G01X624338Y188567D02*
X621383D01*
G01X621730Y172417D02*
X621313D01*
G01X621730Y173567D02*
X621313D01*
G01X621730D02*
X621313D01*
G01X621730Y172417D02*
X621313D01*
G01X607551Y423761D02*
X604693Y419459D01*
G01X765742Y532276D02*
X607551Y423761D01*
G01X764884Y533083D02*
X606716Y424584D01*
G01X607551Y423761D02*
X604693Y419459D01*
G01X764884Y533083D02*
X606716Y424584D01*
G01X765742Y532276D02*
X607551Y423761D01*
G01X642503Y636927D02*
X656088Y698205D01*
G01X641424Y637374D02*
X650126Y676629D01*
G01X637637Y629290D02*
X642503Y636927D01*
G01X636804Y630123D02*
X641424Y637374D01*
G01X632103Y625764D02*
X637637Y629290D01*
G01X631656Y626843D02*
X636804Y630123D01*
G01X630075Y625314D02*
X632103Y625764D01*
G01X629948Y626464D02*
X631656Y626843D01*
G01X628429Y625314D02*
X630075D01*
G01X628147Y626464D02*
X629948D01*
G01X642503Y636927D02*
X656088Y698205D01*
G01X642503Y636927D02*
X656088Y698205D01*
G01X642503Y636927D02*
X656088Y698205D01*
G01X642503Y636927D02*
X656088Y698205D01*
G01X641424Y637374D02*
X650126Y676629D01*
G01X642503Y636927D02*
X656088Y698205D01*
G01X636804Y630123D02*
X641424Y637374D01*
G01X637637Y629290D02*
X642503Y636927D01*
G01X631656Y626843D02*
X636804Y630123D01*
G01X632103Y625764D02*
X637637Y629290D01*
G01X629948Y626464D02*
X631656Y626843D01*
G01X630075Y625314D02*
X632103Y625764D01*
G01X628147Y626464D02*
X629948D01*
G01X628429Y625314D02*
X630075D01*
G01X621398Y641323D02*
X624338D01*
G01X621313Y640173D02*
X624338D01*
G01X621313D02*
X624338D01*
G01X621398Y641323D02*
X624338D01*
G01X621730Y625173D02*
X621313D01*
G01X621730Y626323D02*
X621313D01*
G01X621730D02*
X621313D01*
G01X621730Y625173D02*
X621313D01*
G01X652529Y687466D02*
X652854Y688931D01*
G01X651620Y683366D02*
X651945Y684830D01*
G01X650711Y679265D02*
X651036Y680730D01*
G01X652529Y687466D02*
X652854Y688931D01*
G01X651620Y683366D02*
X651945Y684830D01*
G01X650711Y679265D02*
X651036Y680730D01*
G01X607931Y952774D02*
X657117Y980377D01*
G01X607368Y953777D02*
X656554Y981380D01*
G01X607368Y953777D02*
X656554Y981380D01*
G01X607931Y952774D02*
X657117Y980377D01*
G01X635820Y1081098D02*
X667816Y1167871D01*
G01X634875Y1081862D02*
X666781Y1168390D01*
G01X631094Y1078107D02*
X635820Y1081098D01*
G01X630760Y1079257D02*
X634875Y1081862D01*
G01X628266Y1078107D02*
X631094D01*
G01X627910Y1079257D02*
X630760D01*
G01X634875Y1081862D02*
X666781Y1168390D01*
G01X635820Y1081098D02*
X667816Y1167871D01*
G01X630760Y1079257D02*
X634875Y1081862D01*
G01X631094Y1078107D02*
X635820Y1081098D01*
G01X627910Y1079257D02*
X630760D01*
G01X628266Y1078107D02*
X631094D01*
G01X621730Y1077929D02*
X621313D01*
G01X621730Y1079079D02*
X621313D01*
G01X621730D02*
X621313D01*
G01X621730Y1077929D02*
X621313D01*
G01X624338Y1094079D02*
X621313D01*
G01X624338Y1092929D02*
X621313D01*
G01X624338D02*
X621313D01*
G01X624338Y1094079D02*
X621313D01*
G01X626293Y1330084D02*
X804464Y1294012D01*
G01X626294Y1331258D02*
X804465Y1295186D01*
G01X612088Y1327241D02*
X626293Y1330084D01*
G01X611663Y1328329D02*
X626294Y1331258D01*
G01D02*
X804465Y1295186D01*
G01X626293Y1330084D02*
X804464Y1294012D01*
G01X611663Y1328329D02*
X626294Y1331258D01*
G01X612088Y1327241D02*
X626293Y1330084D01*
G01X625848Y1336390D02*
X801685Y1300792D01*
G01X625849Y1337564D02*
X801686Y1301966D01*
G01X625849Y1337564D02*
X801686Y1301966D01*
G01X625848Y1336390D02*
X801685Y1300792D01*
G01X624308Y1342913D02*
X800001Y1307348D01*
G01X624309Y1344087D02*
X800002Y1308522D01*
G01X624309Y1344087D02*
X800002Y1308522D01*
G01X624308Y1342913D02*
X800001Y1307348D01*
G01X623569Y1349509D02*
X798130Y1314174D01*
G01X623570Y1350683D02*
X798131Y1315348D01*
G01X623570Y1350683D02*
X798131Y1315348D01*
G01X623569Y1349509D02*
X798130Y1314174D01*
G01X658658Y497107D02*
X720418Y548900D01*
G01X658122Y498160D02*
X719570Y549690D01*
G01X658122Y498160D02*
X719570Y549690D01*
G01X658658Y497107D02*
X720418Y548900D01*
G01X653438Y691567D02*
X655017Y698689D01*
G01X653438Y691567D02*
X655017Y698689D01*
G01X656088Y698205D02*
X768963Y853530D01*
G01X655018Y698689D02*
X767891Y854012D01*
G01X655018Y698689D02*
X767891Y854012D01*
G01X656088Y698205D02*
X768963Y853530D01*
G01X664349Y957849D02*
X740564Y1000764D01*
G01X689918Y973567D02*
X739999Y1001767D01*
G01X663533Y958710D02*
X689918Y973567D01*
G01D02*
X739999Y1001767D01*
G01X664349Y957849D02*
X740564Y1000764D01*
G01X663533Y958710D02*
X689918Y973567D01*
G01X664349Y957849D02*
X740564Y1000764D01*
G01X657117Y980377D02*
X762540Y1039541D01*
G01X656554Y981380D02*
X761723Y1040402D01*
G01X656554Y981380D02*
X761723Y1040402D01*
G01X657117Y980377D02*
X762540Y1039541D01*
G01X667816Y1167871D02*
X699459Y1216593D01*
G01X666781Y1168390D02*
X698627Y1217425D01*
G01X666781Y1168390D02*
X698627Y1217425D01*
G01X667816Y1167871D02*
X699459Y1216593D01*
G01D02*
X719844Y1229831D01*
G01X698627Y1217425D02*
X719332Y1230870D01*
G01X698627Y1217425D02*
X719332Y1230870D01*
G01X699459Y1216593D02*
X719844Y1229831D01*
G01X748551Y188567D02*
X745526D01*
G01X748551Y187417D02*
X745526D01*
G01X748551D02*
X745526D01*
G01X748551Y188567D02*
X745526D01*
G01X745943Y172417D02*
X745526D01*
G01X745943Y173567D02*
X745526D01*
G01X745943D02*
X745526D01*
G01X745943Y172417D02*
X745526D01*
G01X728846Y528053D02*
X721363Y522966D01*
G01X727943Y528831D02*
X720716Y523918D01*
G01X787654Y650315D02*
X728846Y528053D01*
G01X786656Y650896D02*
X727943Y528831D01*
G01D02*
X720716Y523918D01*
G01X728846Y528053D02*
X721363Y522966D01*
G01X786656Y650896D02*
X727943Y528831D01*
G01X787654Y650315D02*
X728846Y528053D01*
G01X720418Y548900D02*
X755388Y597235D01*
G01X719570Y549690D02*
X754316Y597717D01*
G01X719570Y549690D02*
X754316Y597717D01*
G01X720418Y548900D02*
X755388Y597235D01*
G01X748551Y641323D02*
X745526D01*
G01X748551Y640173D02*
X745526D01*
G01X748551D02*
X745526D01*
G01X748551Y641323D02*
X745526D01*
G01X745943Y625173D02*
X745526D01*
G01X745943Y626323D02*
X745526D01*
G01X745943D02*
X745526D01*
G01X745943Y625173D02*
X745526D01*
G01X740564Y1000764D02*
X773151Y1019113D01*
G01X739999Y1001767D02*
X772334Y1019973D01*
G01X739999Y1001767D02*
X772334Y1019973D01*
G01X740564Y1000764D02*
X773151Y1019113D01*
G01X745943Y1077929D02*
X745526D01*
G01X745943Y1079079D02*
X745526D01*
G01X745943D02*
X745526D01*
G01X745943Y1077929D02*
X745526D01*
G01X748551Y1094079D02*
X745526D01*
G01X748551Y1092929D02*
X745526D01*
G01X748551D02*
X745526D01*
G01X748551Y1094079D02*
X745526D01*
G01X719844Y1229831D02*
X933443Y1312513D01*
G01X719332Y1230870D02*
X916769Y1307293D01*
G01X719844Y1229831D02*
X933443Y1312513D01*
G01X719844Y1229831D02*
X933443Y1312513D01*
G01X719844Y1229831D02*
X933443Y1312513D01*
G01X719844Y1229831D02*
X933443Y1312513D01*
G01X719332Y1230870D02*
X916769Y1307293D01*
G01X719844Y1229831D02*
X933443Y1312513D01*
G01X754600Y172543D02*
X752147D01*
G01X754266Y173693D02*
X752175D01*
G01X759571Y175689D02*
X754600Y172543D01*
G01X758749Y176531D02*
X754266Y173693D01*
G01X769797Y190997D02*
X759571Y175689D01*
G01X768717Y191451D02*
X758749Y176531D01*
G01X773248Y207425D02*
X769797Y190997D01*
G01X770392Y199426D02*
X768717Y191451D01*
G01X772068Y207404D02*
X770392Y199427D01*
G01X750912Y297917D02*
X773248Y207425D01*
G01X749726Y297920D02*
X772068Y207404D01*
G01X754266Y173693D02*
X752175D01*
G01X754600Y172543D02*
X752147D01*
G01X758749Y176531D02*
X754266Y173693D01*
G01X759571Y175689D02*
X754600Y172543D01*
G01X768717Y191451D02*
X758749Y176531D01*
G01X769797Y190997D02*
X759571Y175689D01*
G01X770392Y199426D02*
X768717Y191451D01*
G01X773248Y207425D02*
X769797Y190997D01*
G01X772068Y207404D02*
X770392Y199427D01*
G01X773248Y207425D02*
X769797Y190997D01*
G01X749726Y297920D02*
X772068Y207404D01*
G01X750912Y297917D02*
X773248Y207425D01*
G01X860594Y734103D02*
X750912Y297917D01*
G01X859408Y734106D02*
X749726Y297920D01*
G01X859408Y734106D02*
X749726Y297920D01*
G01X860594Y734103D02*
X750912Y297917D01*
G01X825397Y619984D02*
X756984Y502633D01*
G01X825397Y619984D02*
X756984Y502633D01*
G01X825397Y619984D02*
X756984Y502633D01*
G01X790130Y561773D02*
X755939Y503126D01*
G01X790130Y561773D02*
X755939Y503126D01*
G01X819699Y622275D02*
X765742Y532276D01*
G01X818624Y622720D02*
X764884Y533083D01*
G01X818624Y622720D02*
X764884Y533083D01*
G01X819699Y622275D02*
X765742Y532276D01*
G01X790182Y584873D02*
X766299Y545036D01*
G01X777254Y565546D02*
X765441Y545843D01*
G01X777254Y565546D02*
X765441Y545843D01*
G01X790182Y584873D02*
X766299Y545036D01*
G01X790182Y584873D02*
X766299Y545036D01*
G01X824321Y620422D02*
X790130Y561774D01*
G01X824321Y620422D02*
X790130Y561774D01*
G01X789195Y585465D02*
X777254Y565546D01*
G01X814024Y624642D02*
X790182Y584873D01*
G01X812949Y625087D02*
X789195Y585465D01*
G01D02*
X777254Y565546D01*
G01X812949Y625087D02*
X789195Y585465D01*
G01X814024Y624642D02*
X790182Y584873D01*
G01X754316Y597717D02*
X772230Y678525D01*
G01X755388Y597235D02*
X764396Y637871D01*
G01X754316Y597717D02*
X772230Y678525D01*
G01X754316Y597717D02*
X772230Y678525D01*
G01X755388Y597235D02*
X764396Y637871D01*
G01X755463Y626219D02*
X766487Y678718D01*
G01X754437Y626931D02*
X765307Y678697D01*
G01X754023Y625308D02*
X755463Y626219D01*
G01X753689Y626458D02*
X754437Y626931D01*
G01X752266Y626458D02*
X753689D01*
G01X752536Y625308D02*
X754023D01*
G01X752266Y626458D02*
X753689D01*
G01X754437Y626931D02*
X765307Y678697D01*
G01X755463Y626219D02*
X766487Y678718D01*
G01X753689Y626458D02*
X754437Y626931D01*
G01X754023Y625308D02*
X755463Y626219D01*
G01X752266Y626458D02*
X753689D01*
G01X754023Y625308D02*
X755463Y626219D01*
G01X752536Y625308D02*
X754023D01*
G01X764396Y637871D02*
X773412Y678539D01*
G01X764396Y637871D02*
X773412Y678539D01*
G01X765307Y678697D02*
X749778Y741608D01*
G01X766487Y678718D02*
X758723Y710170D01*
G01X765307Y678697D02*
X749778Y741608D01*
G01X765307Y678697D02*
X749778Y741608D01*
G01X766487Y678718D02*
X758723Y710170D01*
G01X829519Y711723D02*
X787654Y650315D01*
G01X828453Y712202D02*
X786656Y650896D01*
G01X828453Y712202D02*
X786656Y650896D01*
G01X829519Y711723D02*
X787654Y650315D01*
G01X773412Y678539D02*
X758981Y737027D01*
G01X772230Y678525D02*
X757801Y737006D01*
G01X772230Y678525D02*
X757801Y737006D01*
G01X773412Y678539D02*
X758981Y737027D01*
G01X750959Y741624D02*
X816756Y1042169D01*
G01X749778Y741608D02*
X815675Y1042613D01*
G01X758723Y710171D02*
X750959Y741624D01*
G01X749778Y741608D02*
X815675Y1042613D01*
G01X750959Y741624D02*
X816756Y1042169D01*
G01X758723Y710171D02*
X750959Y741624D01*
G01X758981Y737027D02*
X821963Y1037335D01*
G01X757801Y737006D02*
X789346Y887417D01*
G01X758981Y737027D02*
X821963Y1037335D01*
G01X757801Y737006D02*
X789346Y887417D01*
G01X758981Y737027D02*
X821963Y1037335D01*
G01X768963Y853530D02*
X811942Y1049178D01*
G01X767891Y854012D02*
X810862Y1049622D01*
G01X767891Y854012D02*
X810862Y1049622D01*
G01X768963Y853530D02*
X811942Y1049178D01*
G01X789346Y887417D02*
X820879Y1037775D01*
G01X789346Y887417D02*
X820879Y1037775D01*
G01X773151Y1019113D02*
X922686Y1255487D01*
G01X772334Y1019973D02*
X902978Y1226486D01*
G01X773151Y1019113D02*
X922686Y1255487D01*
G01X773151Y1019113D02*
X922686Y1255487D01*
G01X773151Y1019113D02*
X922686Y1255487D01*
G01X773151Y1019113D02*
X922686Y1255487D01*
G01X772334Y1019973D02*
X902978Y1226486D01*
G01X773151Y1019113D02*
X922686Y1255487D01*
G01X768252Y1024060D02*
X753004Y1015479D01*
G01X917709Y1260256D02*
X768252Y1024060D01*
G01X916953Y1261212D02*
X767435Y1024920D01*
G01X768252Y1024060D02*
X753004Y1015479D01*
G01X916953Y1261212D02*
X767435Y1024920D01*
G01X917709Y1260256D02*
X768252Y1024060D01*
G01X766334Y1032652D02*
X914467Y1266894D01*
G01X765517Y1033512D02*
X901027Y1247793D01*
G01X766334Y1032652D02*
X914467Y1266894D01*
G01X766334Y1032652D02*
X914467Y1266894D01*
G01X766334Y1032652D02*
X914467Y1266894D01*
G01X766334Y1032652D02*
X914467Y1266894D01*
G01X765517Y1033512D02*
X901027Y1247793D01*
G01X766334Y1032652D02*
X914467Y1266894D01*
G01X754473Y1078087D02*
X762245Y1083014D01*
G01X754139Y1079237D02*
X761411Y1083847D01*
G01X752359Y1078087D02*
X754473D01*
G01X752043Y1079237D02*
X754139D01*
G01D02*
X761411Y1083847D01*
G01X754473Y1078087D02*
X762245Y1083014D01*
G01X752043Y1079237D02*
X754139D01*
G01X752359Y1078087D02*
X754473D01*
G01X762540Y1039541D02*
X909569Y1271927D01*
G01X761723Y1040402D02*
X908813Y1272883D01*
G01X761723Y1040402D02*
X908813Y1272883D01*
G01X762540Y1039541D02*
X909569Y1271927D01*
G01X762245Y1083014D02*
X887547Y1281062D01*
G01X761411Y1083847D02*
X886737Y1281934D01*
G01X761411Y1083847D02*
X886737Y1281934D01*
G01X762245Y1083014D02*
X887547Y1281062D01*
G01X853942Y733846D02*
X825397Y619984D01*
G01X852756Y733848D02*
X824321Y620422D01*
G01X852756Y733848D02*
X824321Y620422D01*
G01X853942Y733846D02*
X825397Y619984D01*
G01X847543Y733402D02*
X819699Y622275D01*
G01X846357Y733404D02*
X818624Y622720D01*
G01X846357Y733404D02*
X818624Y622720D01*
G01X847543Y733402D02*
X819699Y622275D01*
G01X841148Y732926D02*
X814024Y624642D01*
G01X839962Y732928D02*
X812949Y625087D01*
G01X839962Y732928D02*
X812949Y625087D01*
G01X841148Y732926D02*
X814024Y624642D01*
G01X834885Y784688D02*
X847543Y733402D01*
G01X840062Y758909D02*
X846357Y733404D01*
G01X840062Y758909D02*
X846357Y733404D01*
G01X834885Y784688D02*
X847543Y733402D01*
G01X834885Y784688D02*
X847543Y733402D01*
G01X818491Y824733D02*
X841148Y732926D01*
G01X817311Y824712D02*
X839962Y732928D01*
G01X817311Y824712D02*
X839962Y732928D01*
G01X818491Y824733D02*
X841148Y732926D01*
G01X833011Y725654D02*
X829519Y711723D01*
G01X831895Y725933D02*
X828453Y712202D01*
G01X834803Y732803D02*
X833011Y725654D01*
G01X833617Y732805D02*
X831895Y725934D01*
G01X812055Y824966D02*
X834803Y732803D01*
G01X810875Y824945D02*
X833617Y732805D01*
G01X831895Y725933D02*
X828453Y712202D01*
G01X833011Y725654D02*
X829519Y711723D01*
G01X833617Y732805D02*
X831895Y725934D01*
G01X834803Y732803D02*
X833011Y725654D01*
G01X810875Y824945D02*
X833617Y732805D01*
G01X812055Y824966D02*
X834803Y732803D01*
G01X838351Y819407D02*
X859408Y734106D01*
G01X838351Y819407D02*
X859408Y734106D01*
G01X838351Y819407D02*
X859408Y734106D01*
G01X831982Y822801D02*
X853942Y733846D01*
G01X830802Y822780D02*
X852756Y733848D01*
G01X830802Y822780D02*
X852756Y733848D01*
G01X831982Y822801D02*
X853942Y733846D01*
G01X833768Y784412D02*
X840061Y758909D01*
G01X832787Y793187D02*
X834885Y784688D01*
G01X829572Y801412D02*
X833768Y784412D01*
G01D02*
X840061Y758909D01*
G01X829572Y801412D02*
X833768Y784412D01*
G01X832787Y793187D02*
X834885Y784688D01*
G01X839531Y819428D02*
X849997Y777032D01*
G01X897965Y1097884D02*
X839531Y819428D01*
G01X896839Y1098120D02*
X838351Y819407D01*
G01X839531Y819428D02*
X849997Y777032D01*
G01X896839Y1098120D02*
X838351Y819407D01*
G01X897965Y1097884D02*
X839531Y819428D01*
G01X897965Y1097884D02*
X839531Y819428D01*
G01X889255Y1095845D02*
X831982Y822801D01*
G01X888171Y1096285D02*
X830802Y822780D01*
G01X888171Y1096285D02*
X830802Y822780D01*
G01X889255Y1095845D02*
X831982Y822801D01*
G01X825115Y824270D02*
X832787Y793187D01*
G01X823935Y824249D02*
X829572Y801412D01*
G01X852527Y954866D02*
X825115Y824270D01*
G01X851593Y956016D02*
X823935Y824249D01*
G01D02*
X829572Y801412D01*
G01X825115Y824270D02*
X832787Y793187D01*
G01X851593Y956016D02*
X823935Y824249D01*
G01X852527Y954866D02*
X825115Y824270D01*
G01X876016Y1098852D02*
X818491Y824733D01*
G01X874932Y1099292D02*
X817311Y824712D01*
G01X874932Y1099292D02*
X817311Y824712D01*
G01X876016Y1098852D02*
X818491Y824733D01*
G01X870085Y1101486D02*
X812055Y824966D01*
G01X869001Y1101926D02*
X810875Y824945D01*
G01X869001Y1101926D02*
X810875Y824945D01*
G01X870085Y1101486D02*
X812055Y824966D01*
G01X816756Y1042169D02*
X947661Y1249063D01*
G01X815675Y1042613D02*
X946903Y1250019D01*
G01X815675Y1042613D02*
X946903Y1250019D01*
G01X816756Y1042169D02*
X947661Y1249063D01*
G01X811942Y1049178D02*
X942150Y1254935D01*
G01X810862Y1049622D02*
X941394Y1255891D01*
G01X810862Y1049622D02*
X941394Y1255891D01*
G01X811942Y1049178D02*
X942150Y1254935D01*
G01X821963Y1037335D02*
X918798Y1190381D01*
G01X820879Y1037775D02*
X917931Y1191163D01*
G01X820879Y1037775D02*
X917931Y1191163D01*
G01X821963Y1037335D02*
X918798Y1190381D01*
G01X804464Y1294012D02*
X934794Y1320108D01*
G01X820938Y1298484D02*
X934402Y1321203D01*
G01X816820Y1297660D02*
X818291Y1297954D01*
G01X812702Y1296835D02*
X814172Y1297130D01*
G01X808583Y1296011D02*
X810054Y1296305D01*
G01X804465Y1295186D02*
X805936Y1295480D01*
G01X820938Y1298484D02*
X934402Y1321203D01*
G01X804464Y1294012D02*
X934794Y1320108D01*
G01X816820Y1297660D02*
X818291Y1297954D01*
G01X804464Y1294012D02*
X934794Y1320108D01*
G01X812702Y1296835D02*
X814172Y1297130D01*
G01X804464Y1294012D02*
X934794Y1320108D01*
G01X808583Y1296011D02*
X810054Y1296305D01*
G01X804464Y1294012D02*
X934794Y1320108D01*
G01X804465Y1295186D02*
X805936Y1295480D01*
G01X804464Y1294012D02*
X934794Y1320108D01*
G01X801685Y1300792D02*
X936053Y1327695D01*
G01X820851Y1305804D02*
X935660Y1328790D01*
G01X816733Y1304979D02*
X818204Y1305274D01*
G01X812614Y1304155D02*
X814085Y1304449D01*
G01X808496Y1303330D02*
X809967Y1303625D01*
G01X801686Y1301966D02*
X805849Y1302800D01*
G01X820851Y1305804D02*
X935660Y1328790D01*
G01X801685Y1300792D02*
X936053Y1327695D01*
G01X816733Y1304979D02*
X818204Y1305274D01*
G01X801685Y1300792D02*
X936053Y1327695D01*
G01X812614Y1304155D02*
X814085Y1304449D01*
G01X801685Y1300792D02*
X936053Y1327695D01*
G01X808496Y1303330D02*
X809967Y1303625D01*
G01X801685Y1300792D02*
X936053Y1327695D01*
G01X801686Y1301966D02*
X805849Y1302800D01*
G01X801685Y1300792D02*
X936053Y1327695D01*
G01X818550Y1311061D02*
X936042Y1334579D01*
G01X818792Y1312283D02*
X935649Y1335674D01*
G01X804485Y1308246D02*
X818550Y1311061D01*
G01X814674Y1311459D02*
X816145Y1311753D01*
G01X810555Y1310634D02*
X812026Y1310929D01*
G01X806437Y1309810D02*
X807908Y1310104D01*
G01X800001Y1307348D02*
X804484Y1308245D01*
G01X800002Y1308522D02*
X803790Y1309280D01*
G01X818792Y1312283D02*
X935649Y1335674D01*
G01X818550Y1311061D02*
X936042Y1334579D01*
G01X814674Y1311459D02*
X816145Y1311753D01*
G01X804485Y1308246D02*
X818550Y1311061D01*
G01X810555Y1310634D02*
X812026Y1310929D01*
G01X804485Y1308246D02*
X818550Y1311061D01*
G01X806437Y1309810D02*
X807908Y1310104D01*
G01X804485Y1308246D02*
X818550Y1311061D01*
G01X800002Y1308522D02*
X803790Y1309280D01*
G01X800001Y1307348D02*
X804484Y1308245D01*
G01X822272Y1319008D02*
X934869Y1341549D01*
G01X822047Y1320136D02*
X934477Y1342644D01*
G01X798130Y1314174D02*
X822272Y1319006D01*
G01X817929Y1319311D02*
X819400Y1319606D01*
G01X813811Y1318487D02*
X815282Y1318781D01*
G01X809693Y1317662D02*
X811163Y1317957D01*
G01X798131Y1315348D02*
X807045Y1317133D01*
G01X822047Y1320136D02*
X934477Y1342644D01*
G01X822272Y1319008D02*
X934869Y1341549D01*
G01X817929Y1319311D02*
X819400Y1319606D01*
G01X798130Y1314174D02*
X822272Y1319006D01*
G01X813811Y1318487D02*
X815282Y1318781D01*
G01X798130Y1314174D02*
X822272Y1319006D01*
G01X809693Y1317662D02*
X811163Y1317957D01*
G01X798130Y1314174D02*
X822272Y1319006D01*
G01X798131Y1315348D02*
X807045Y1317133D01*
G01X798130Y1314174D02*
X822272Y1319006D01*
G01X849997Y777032D02*
X860594Y734103D01*
G01X849997Y777032D02*
X860594Y734103D01*
G01X882397Y1097173D02*
X852528Y954866D01*
G01X866337Y1026256D02*
X851594Y956016D01*
G01X866337Y1026256D02*
X851594Y956016D01*
G01X882397Y1097173D02*
X852528Y954866D01*
G01X882397Y1097173D02*
X852528Y954866D01*
G01X881313Y1097613D02*
X866337Y1026256D01*
G01X881313Y1097613D02*
X866337Y1026256D01*
G01X939616Y1175447D02*
X889255Y1095845D01*
G01X938747Y1176226D02*
X888171Y1096285D01*
G01X938747Y1176226D02*
X888171Y1096285D01*
G01X939616Y1175447D02*
X889255Y1095845D01*
G01X934003Y1178738D02*
X882397Y1097173D01*
G01X933136Y1179519D02*
X881313Y1097613D01*
G01X933136Y1179519D02*
X881313Y1097613D01*
G01X934003Y1178738D02*
X882397Y1097173D01*
G01X929185Y1182887D02*
X876016Y1098852D01*
G01X928318Y1183669D02*
X874932Y1099292D01*
G01X928318Y1183669D02*
X874932Y1099292D01*
G01X929185Y1182887D02*
X876016Y1098852D01*
G01X923907Y1186558D02*
X870085Y1101486D01*
G01X923040Y1187340D02*
X869001Y1101926D01*
G01X923040Y1187340D02*
X869001Y1101926D01*
G01X923907Y1186558D02*
X870085Y1101486D01*
G01X889541Y1282127D02*
X905032Y1290400D01*
G01X893375Y1285479D02*
X894698Y1286186D01*
G01X887547Y1281062D02*
X889540Y1282126D01*
G01X886737Y1281934D02*
X890994Y1284207D01*
G01X889541Y1282127D02*
X905032Y1290400D01*
G01X889541Y1282127D02*
X905032Y1290400D01*
G01X893375Y1285479D02*
X894698Y1286186D01*
G01X889541Y1282127D02*
X905032Y1290400D01*
G01X886737Y1281934D02*
X890994Y1284207D01*
G01X887547Y1281062D02*
X889540Y1282126D01*
G01X896881Y1098324D02*
X896838Y1098120D01*
G01X944540Y1171496D02*
X897965Y1097884D01*
G01X943673Y1172278D02*
X896881Y1098324D01*
G01D02*
X896838Y1098120D01*
G01X943673Y1172278D02*
X896881Y1098324D01*
G01X944540Y1171496D02*
X897965Y1097884D01*
G01X959905Y1191434D02*
X939616Y1175447D01*
G01X959346Y1192458D02*
X938749Y1176228D01*
G01X959346Y1192458D02*
X938749Y1176228D01*
G01X959905Y1191434D02*
X939616Y1175447D01*
G01X957158Y1196985D02*
X934003Y1178738D01*
G01X956599Y1198009D02*
X933136Y1179519D01*
G01X956599Y1198009D02*
X933136Y1179519D01*
G01X957158Y1196985D02*
X934003Y1178738D01*
G01X941460Y1192560D02*
X929185Y1182887D01*
G01X934610Y1188627D02*
X928318Y1183669D01*
G01X935911Y1189653D02*
X934610Y1188627D01*
G01X940748Y1193464D02*
X935911Y1189653D01*
G01X953738Y1202235D02*
X941460Y1192560D01*
G01X946887Y1198302D02*
X940748Y1193464D01*
G01X934610Y1188627D02*
X928318Y1183669D01*
G01X941460Y1192560D02*
X929185Y1182887D01*
G01X935911Y1189653D02*
X934610Y1188627D01*
G01X941460Y1192560D02*
X929185Y1182887D01*
G01X940748Y1193464D02*
X935911Y1189653D01*
G01X941460Y1192560D02*
X929185Y1182887D01*
G01X946887Y1198302D02*
X940748Y1193464D01*
G01X953738Y1202235D02*
X941460Y1192560D01*
G01X953738Y1202235D02*
X941460Y1192560D01*
G01X953738Y1202235D02*
X941460Y1192560D01*
G01X950979Y1207889D02*
X923907Y1186558D01*
G01X950420Y1208913D02*
X923040Y1187340D01*
G01X950420Y1208913D02*
X923040Y1187340D01*
G01X950979Y1207889D02*
X923907Y1186558D01*
G01X918798Y1190381D02*
X948239Y1213580D01*
G01X917931Y1191163D02*
X947680Y1214604D01*
G01X917931Y1191163D02*
X947680Y1214604D01*
G01X918798Y1190381D02*
X948239Y1213580D01*
G01X942150Y1254935D02*
X1066016Y1297692D01*
G01X941394Y1255891D02*
X1065823Y1298842D01*
G01X941394Y1255891D02*
X1065823Y1298842D01*
G01X942150Y1254935D02*
X1066016Y1297692D01*
G01X922686Y1255487D02*
X1066824Y1305204D01*
G01X921929Y1256443D02*
X1066631Y1306354D01*
G01X911157Y1239416D02*
X921929Y1256443D01*
G01X908912Y1235867D02*
X909714Y1237135D01*
G01X906667Y1232318D02*
X907469Y1233585D01*
G01X904421Y1228768D02*
X905223Y1230036D01*
G01X921929Y1256443D02*
X1066631Y1306354D01*
G01X922686Y1255487D02*
X1066824Y1305204D01*
G01X911157Y1239416D02*
X921929Y1256443D01*
G01X908912Y1235867D02*
X909714Y1237135D01*
G01X906667Y1232318D02*
X907469Y1233585D01*
G01X904421Y1228768D02*
X905223Y1230036D01*
G01X987321Y1284267D02*
X917709Y1260256D01*
G01X944908Y1270856D02*
X916953Y1261212D01*
G01X944908Y1270856D02*
X916953Y1261212D01*
G01X987321Y1284267D02*
X917709Y1260256D01*
G01X987321Y1284267D02*
X917709Y1260256D01*
G01X987321Y1284267D02*
X917709Y1260256D01*
G01X987321Y1284267D02*
X917709Y1260256D01*
G01X987321Y1284267D02*
X917709Y1260256D01*
G01X913710Y1267850D02*
X990092Y1294199D01*
G01X914467Y1266894D02*
X990467Y1293111D01*
G01X913710Y1267850D02*
X990092Y1294199D01*
G01X909204Y1260724D02*
X913710Y1267850D01*
G01X906959Y1257175D02*
X907761Y1258442D01*
G01X904715Y1253625D02*
X905516Y1254893D01*
G01X902470Y1250075D02*
X903271Y1251343D01*
G01X913710Y1267850D02*
X990092Y1294199D01*
G01X914467Y1266894D02*
X990467Y1293111D01*
G01X909204Y1260724D02*
X913710Y1267850D01*
G01X906959Y1257175D02*
X907761Y1258442D01*
G01X904715Y1253625D02*
X905516Y1254893D01*
G01X902470Y1250075D02*
X903271Y1251343D01*
G01X909569Y1271927D02*
X1067968Y1326464D01*
G01X908813Y1272883D02*
X1050101Y1321529D01*
G01X909569Y1271927D02*
X1067968Y1326464D01*
G01X909569Y1271927D02*
X1067968Y1326464D01*
G01X909569Y1271927D02*
X1067968Y1326464D01*
G01X909569Y1271927D02*
X1067968Y1326464D01*
G01X909569Y1271927D02*
X1067968Y1326464D01*
G01X908813Y1272883D02*
X1050101Y1321529D01*
G01X909569Y1271927D02*
X1067968Y1326464D01*
G01X905031Y1290400D02*
X1065445Y1376070D01*
G01X904490Y1291415D02*
X1065157Y1377220D01*
G01X905032Y1290400D02*
X905031D01*
G01X904490Y1291415D02*
X1065157Y1377220D01*
G01X900785Y1289436D02*
X902108Y1290143D01*
G01X897080Y1287458D02*
X898403Y1288164D01*
G01X904490Y1291415D02*
X1065157Y1377220D01*
G01X905031Y1290400D02*
X1065445Y1376070D01*
G01X905032Y1290400D02*
X905031D01*
G01X900785Y1289436D02*
X902108Y1290143D01*
G01X897080Y1287458D02*
X898403Y1288164D01*
G01X933443Y1312513D02*
X1065210Y1382905D01*
G01X932962Y1313561D02*
X1064922Y1384055D01*
G01X931038Y1312816D02*
X932962Y1313561D01*
G01X927121Y1311300D02*
X928520Y1311842D01*
G01X923204Y1309784D02*
X924603Y1310325D01*
G01X919287Y1308268D02*
X920686Y1308809D01*
G01X932962Y1313561D02*
X1064922Y1384055D01*
G01X933443Y1312513D02*
X1065210Y1382905D01*
G01X931038Y1312816D02*
X932962Y1313561D01*
G01X927121Y1311300D02*
X928520Y1311842D01*
G01X923204Y1309784D02*
X924603Y1310325D01*
G01X919287Y1308268D02*
X920686Y1308809D01*
G01X934795Y1320108D02*
X1066092Y1390243D01*
G01X934402Y1321203D02*
X1065804Y1391393D01*
G01X934402Y1321203D02*
X1065804Y1391393D01*
G01X934795Y1320108D02*
X1066092Y1390243D01*
G01X936053Y1327695D02*
X1066392Y1397330D01*
G01X935660Y1328790D02*
X1066104Y1398480D01*
G01X935660Y1328790D02*
X1066104Y1398480D01*
G01X936053Y1327695D02*
X1066392Y1397330D01*
G01X936042Y1334579D02*
X1066737Y1404405D01*
G01X935649Y1335674D02*
X1066449Y1405555D01*
G01X935649Y1335674D02*
X1066449Y1405555D01*
G01X936042Y1334579D02*
X1066737Y1404405D01*
G01X934869Y1341549D02*
X1064724Y1410908D01*
G01X934477Y1342644D02*
X1064436Y1412058D01*
G01X934477Y1342644D02*
X1064436Y1412058D01*
G01X934869Y1341549D02*
X1064724Y1410908D01*
G01X962734Y1185833D02*
X944540Y1171496D01*
G01X952925Y1179568D02*
X943673Y1172278D01*
G01X962023Y1186737D02*
X952925Y1179568D01*
G01D02*
X943673Y1172278D01*
G01X962734Y1185833D02*
X944540Y1171496D01*
G01X962023Y1186737D02*
X952925Y1179568D01*
G01X962734Y1185833D02*
X944540Y1171496D01*
G01X962734Y1185833D02*
X944540Y1171496D01*
G01X962734Y1185833D02*
X944540Y1171496D01*
G01X962022Y1186737D02*
X962023D01*
G01X962175Y1186857D02*
X962022Y1186737D01*
G01X1021164Y1205991D02*
X962734Y1185833D01*
G01X1020971Y1207141D02*
X962175Y1186857D01*
G01X962022Y1186737D02*
X962023D01*
G01X962175Y1186857D02*
X962022Y1186737D01*
G01X1020971Y1207141D02*
X962175Y1186857D01*
G01X1021164Y1205991D02*
X962734Y1185833D01*
G01X1022651Y1213078D02*
X959905Y1191434D01*
G01X1022458Y1214228D02*
X959346Y1192458D01*
G01X1022458Y1214228D02*
X959346Y1192458D01*
G01X1022651Y1213078D02*
X959905Y1191434D01*
G01X1024349Y1220164D02*
X957158Y1196985D01*
G01X1024156Y1221314D02*
X956599Y1198009D01*
G01X1024156Y1221314D02*
X956599Y1198009D01*
G01X1024349Y1220164D02*
X957158Y1196985D01*
G01X953027Y1203139D02*
X946887Y1198302D01*
G01X953182Y1203261D02*
X953027Y1203139D01*
G01X1026249Y1227251D02*
X953738Y1202235D01*
G01X1026056Y1228401D02*
X953182Y1203261D01*
G01X953027Y1203139D02*
X946887Y1198302D01*
G01X953182Y1203261D02*
X953027Y1203139D01*
G01X1026056Y1228401D02*
X953182Y1203261D01*
G01X1026249Y1227251D02*
X953738Y1202235D01*
G01X1027644Y1234338D02*
X950979Y1207889D01*
G01X1027451Y1235488D02*
X950420Y1208913D01*
G01X1027451Y1235488D02*
X950420Y1208913D01*
G01X1027644Y1234338D02*
X950979Y1207889D01*
G01X948239Y1213580D02*
X1028955Y1241424D01*
G01X947680Y1214604D02*
X1028762Y1242574D01*
G01X947680Y1214604D02*
X1028762Y1242574D01*
G01X948239Y1213580D02*
X1028955Y1241424D01*
G01X947661Y1249063D02*
X1069357Y1291040D01*
G01X962785Y1255497D02*
X1069164Y1292190D01*
G01X958814Y1254128D02*
X960232Y1254617D01*
G01X954844Y1252758D02*
X956262Y1253247D01*
G01X950873Y1251389D02*
X952291Y1251878D01*
G01X946903Y1250019D02*
X948321Y1250508D01*
G01X962785Y1255497D02*
X1069164Y1292190D01*
G01X947661Y1249063D02*
X1069357Y1291040D01*
G01X958814Y1254128D02*
X960232Y1254617D01*
G01X947661Y1249063D02*
X1069357Y1291040D01*
G01X954844Y1252758D02*
X956262Y1253247D01*
G01X947661Y1249063D02*
X1069357Y1291040D01*
G01X950873Y1251389D02*
X952291Y1251878D01*
G01X947661Y1249063D02*
X1069357Y1291040D01*
G01X946903Y1250019D02*
X948321Y1250508D01*
G01X947661Y1249063D02*
X1069357Y1291040D01*
G01X972484Y1280367D02*
X944908Y1270856D01*
G01X972484Y1280367D02*
X944908Y1270856D01*
G01X976454Y1281737D02*
X975036Y1281248D01*
G01X980425Y1283107D02*
X979007Y1282618D01*
G01X984395Y1284476D02*
X982977Y1283987D01*
G01X1068556Y1312290D02*
X987321Y1284269D01*
G01X1068363Y1313440D02*
X986947Y1285357D01*
G01X976454Y1281737D02*
X975036Y1281248D01*
G01X980425Y1283107D02*
X979007Y1282618D01*
G01X984395Y1284476D02*
X982977Y1283987D01*
G01X1068363Y1313440D02*
X986947Y1285357D01*
G01X1068556Y1312290D02*
X987321Y1284269D01*
G01X990541Y1293137D02*
X1066611Y1319377D01*
G01X990099Y1294202D02*
X1066418Y1320527D01*
G01X990472Y1293113D02*
X990539Y1293136D01*
G01X990099Y1294202D02*
X1066418Y1320527D01*
G01X990099Y1294202D02*
X1066418Y1320527D01*
G01X990541Y1293137D02*
X1066611Y1319377D01*
G01X990472Y1293113D02*
X990539Y1293136D01*
G01X990472Y1293113D02*
X990539Y1293136D01*
G01X1071925Y1205991D02*
X1021164D01*
G01X1048068Y1207141D02*
X1020971D01*
G01X1048068D02*
X1020971D01*
G01X1071925Y1205991D02*
X1021164D01*
G01X1071925D02*
X1021164D01*
G01X1071925D02*
X1021164D01*
G01X1071925D02*
X1021164D01*
G01X1071925D02*
X1021164D01*
G01X1071925Y1213078D02*
X1022651D01*
G01X1047306Y1214228D02*
X1022458D01*
G01X1047306D02*
X1022458D01*
G01X1071925Y1213078D02*
X1022651D01*
G01X1071925D02*
X1022651D01*
G01X1071925D02*
X1022651D01*
G01X1071925D02*
X1022651D01*
G01X1071925D02*
X1022651D01*
G01X1071925Y1220164D02*
X1024349D01*
G01X1047412Y1221314D02*
X1024156D01*
G01X1047412D02*
X1024156D01*
G01X1071925Y1220164D02*
X1024349D01*
G01X1071925D02*
X1024349D01*
G01X1071925D02*
X1024349D01*
G01X1071925D02*
X1024349D01*
G01X1071925D02*
X1024349D01*
G01X1071925Y1227251D02*
X1026249D01*
G01X1071925D02*
X1026249D01*
G01X1071925D02*
X1026249D01*
G01X1071925D02*
X1026249D01*
G01X1071925D02*
X1026249D01*
G01X1071925D02*
X1026249D01*
G01X1047413Y1228401D02*
X1026056D01*
G01X1047413D02*
X1026056D01*
G01X1071925Y1234338D02*
X1027644D01*
G01X1047414Y1235488D02*
X1027451D01*
G01X1047414D02*
X1027451D01*
G01X1071925Y1234338D02*
X1027644D01*
G01X1071925D02*
X1027644D01*
G01X1071925D02*
X1027644D01*
G01X1071925D02*
X1027644D01*
G01X1071925D02*
X1027644D01*
G01X1028955Y1241424D02*
X1071925D01*
G01X1028762Y1242574D02*
X1047414D01*
G01X1028955Y1241424D02*
X1071925D01*
G01X1028955D02*
X1071925D01*
G01X1028955D02*
X1071925D01*
G01X1028955D02*
X1071925D01*
G01X1028762Y1242574D02*
X1047414D01*
G01X1028955Y1241424D02*
X1071925D01*
G01X1052268Y1207141D02*
X1050768D01*
G01X1056468D02*
X1054968D01*
G01X1060668D02*
X1059168D01*
G01X1071925D02*
X1063368D01*
G01X1073575Y1207641D02*
G02X1071925Y1205991I-1650J0D01*
G01X1072425Y1207641D02*
G02X1071925Y1207141I-500J0D01*
G01X1073575Y1209362D02*
Y1207641D01*
G01X1072425Y1209362D02*
Y1207641D01*
G01X1052268Y1207141D02*
X1050768D01*
G01X1056468D02*
X1054968D01*
G01X1060668D02*
X1059168D01*
G01X1071925D02*
X1063368D01*
G01X1072425Y1207641D02*
G02X1071925Y1207141I-500J0D01*
G01X1073575Y1207641D02*
G02X1071925Y1205991I-1650J0D01*
G01X1072425Y1209362D02*
Y1207641D01*
G01X1073575Y1209362D02*
Y1207641D01*
G01X1051506Y1214228D02*
X1050006D01*
G01X1055706D02*
X1054206D01*
G01X1059906D02*
X1058406D01*
G01X1071925D02*
X1062606D01*
G01X1073575Y1214728D02*
G02X1071925Y1213078I-1650J0D01*
G01X1072425Y1214728D02*
G02X1071925Y1214228I-500J0D01*
G01X1073575Y1216449D02*
Y1214728D01*
G01X1072425Y1216449D02*
Y1214728D01*
G01X1051506Y1214228D02*
X1050006D01*
G01X1055706D02*
X1054206D01*
G01X1059906D02*
X1058406D01*
G01X1071925D02*
X1062606D01*
G01X1072425Y1214728D02*
G02X1071925Y1214228I-500J0D01*
G01X1073575Y1214728D02*
G02X1071925Y1213078I-1650J0D01*
G01X1072425Y1216449D02*
Y1214728D01*
G01X1073575Y1216449D02*
Y1214728D01*
G01X1051612Y1221314D02*
X1050112D01*
G01X1055812D02*
X1054312D01*
G01X1060012D02*
X1058512D01*
G01X1071925D02*
X1062712D01*
G01X1073575Y1221814D02*
G02X1071925Y1220164I-1650J0D01*
G01X1072425Y1221814D02*
G02X1071925Y1221314I-500J0D01*
G01X1073575Y1223535D02*
Y1221814D01*
G01X1072425Y1223535D02*
Y1221814D01*
G01X1051612Y1221314D02*
X1050112D01*
G01X1055812D02*
X1054312D01*
G01X1060012D02*
X1058512D01*
G01X1071925D02*
X1062712D01*
G01X1072425Y1221814D02*
G02X1071925Y1221314I-500J0D01*
G01X1073575Y1221814D02*
G02X1071925Y1220164I-1650J0D01*
G01X1072425Y1223535D02*
Y1221814D01*
G01X1073575Y1223535D02*
Y1221814D01*
G01Y1228901D02*
G02X1071925Y1227251I-1650J0D01*
G01X1073575Y1228901D02*
G02X1071925Y1227251I-1650J0D01*
G01X1051613Y1228401D02*
X1050113D01*
G01X1055813D02*
X1054313D01*
G01X1060013D02*
X1058513D01*
G01X1071925D02*
X1062713D01*
G01X1072425Y1228901D02*
G02X1071925Y1228401I-500J0D01*
G01X1073575Y1230622D02*
Y1228901D01*
G01X1072425Y1230622D02*
Y1228901D01*
G01X1051613Y1228401D02*
X1050113D01*
G01X1055813D02*
X1054313D01*
G01X1060013D02*
X1058513D01*
G01X1071925D02*
X1062713D01*
G01X1072425Y1228901D02*
G02X1071925Y1228401I-500J0D01*
G01X1072425Y1230622D02*
Y1228901D01*
G01X1073575Y1230622D02*
Y1228901D01*
G01X1051614Y1235488D02*
X1050114D01*
G01X1055814D02*
X1054314D01*
G01X1060014D02*
X1058514D01*
G01X1071925D02*
X1062714D01*
G01X1073575Y1235988D02*
G02X1071925Y1234338I-1650J0D01*
G01X1072425Y1235988D02*
G02X1071925Y1235488I-500J0D01*
G01X1073575Y1237709D02*
Y1235988D01*
G01X1072425Y1237709D02*
Y1235988D01*
G01X1051614Y1235488D02*
X1050114D01*
G01X1055814D02*
X1054314D01*
G01X1060014D02*
X1058514D01*
G01X1071925D02*
X1062714D01*
G01X1072425Y1235988D02*
G02X1071925Y1235488I-500J0D01*
G01X1073575Y1235988D02*
G02X1071925Y1234338I-1650J0D01*
G01X1072425Y1237709D02*
Y1235988D01*
G01X1073575Y1237709D02*
Y1235988D01*
G01Y1243074D02*
Y1244795D01*
G01X1072425Y1243074D02*
Y1244795D01*
G01X1071925Y1241424D02*
G03X1073575Y1243074I0J1650D01*
G01X1071925Y1242574D02*
G03X1072425Y1243074I0J500D01*
G01X1062714Y1242574D02*
X1071925D01*
G01X1058514D02*
X1060014D01*
G01X1054314D02*
X1055814D01*
G01X1050114D02*
X1051614D01*
G01X1072425Y1243074D02*
Y1244795D01*
G01X1073575Y1243074D02*
Y1244795D01*
G01X1071925Y1242574D02*
G03X1072425Y1243074I0J500D01*
G01X1071925Y1241424D02*
G03X1073575Y1243074I0J1650D01*
G01X1062714Y1242574D02*
X1071925D01*
G01X1058514D02*
X1060014D01*
G01X1054314D02*
X1055814D01*
G01X1050114D02*
X1051614D01*
G01X1073575Y1292690D02*
Y1294402D01*
G01X1072425Y1292690D02*
Y1294402D01*
G01X1071925Y1291040D02*
G03X1073575Y1292690I0J1650D01*
G01X1071925Y1292190D02*
G03X1072425Y1292690I0J500D01*
G01X1069357Y1291040D02*
X1071925D01*
G01X1069164Y1292190D02*
X1071925D01*
G01X1072425Y1292690D02*
Y1294402D01*
G01X1073575Y1292690D02*
Y1294402D01*
G01X1071925Y1292190D02*
G03X1072425Y1292690I0J500D01*
G01X1071925Y1291040D02*
G03X1073575Y1292690I0J1650D01*
G01X1069164Y1292190D02*
X1071925D01*
G01X1069357Y1291040D02*
X1071925D01*
G01X1073575Y1299342D02*
Y1301488D01*
G01X1072425Y1299342D02*
Y1301488D01*
G01X1071925Y1297692D02*
G03X1073575Y1299342I0J1650D01*
G01X1071925Y1298842D02*
G03X1072425Y1299342I0J500D01*
G01X1066016Y1297692D02*
X1071925D01*
G01X1065823Y1298842D02*
X1071925D01*
G01X1072425Y1299342D02*
Y1301488D01*
G01X1073575Y1299342D02*
Y1301488D01*
G01X1071925Y1298842D02*
G03X1072425Y1299342I0J500D01*
G01X1071925Y1297692D02*
G03X1073575Y1299342I0J1650D01*
G01X1065823Y1298842D02*
X1071925D01*
G01X1066016Y1297692D02*
X1071925D01*
G01X1073575Y1306854D02*
Y1308575D01*
G01X1072425Y1306854D02*
Y1308575D01*
G01X1071925Y1305204D02*
G03X1073575Y1306854I0J1650D01*
G01X1071925Y1306354D02*
G03X1072425Y1306854I0J500D01*
G01X1066824Y1305204D02*
X1071925D01*
G01X1066631Y1306354D02*
X1071925D01*
G01X1072425Y1306854D02*
Y1308575D01*
G01X1073575Y1306854D02*
Y1308575D01*
G01X1071925Y1306354D02*
G03X1072425Y1306854I0J500D01*
G01X1071925Y1305204D02*
G03X1073575Y1306854I0J1650D01*
G01X1066631Y1306354D02*
X1071925D01*
G01X1066824Y1305204D02*
X1071925D01*
G01X1071564Y1312290D02*
X1068556D01*
G01X1071564Y1313440D02*
X1068363D01*
G01X1073575Y1314301D02*
G02X1071564Y1312290I-2011J0D01*
G01X1072425Y1314301D02*
G02X1071564Y1313440I-861J0D01*
G01X1073575Y1315661D02*
Y1314301D01*
G01X1072425Y1315661D02*
Y1314301D01*
G01X1071564Y1313440D02*
X1068363D01*
G01X1071564Y1312290D02*
X1068556D01*
G01X1072425Y1314301D02*
G02X1071564Y1313440I-861J0D01*
G01X1073575Y1314301D02*
G02X1071564Y1312290I-2011J0D01*
G01X1072425Y1315661D02*
Y1314301D01*
G01X1073575Y1315661D02*
Y1314301D01*
G01Y1321027D02*
Y1322748D01*
G01X1072425Y1321027D02*
Y1322748D01*
G01X1071925Y1319377D02*
G03X1073575Y1321027I0J1650D01*
G01X1071925Y1320527D02*
G03X1072425Y1321027I0J500D01*
G01X1066611Y1319377D02*
X1071925D01*
G01X1066418Y1320527D02*
X1071925D01*
G01X1072425Y1321027D02*
Y1322748D01*
G01X1073575Y1321027D02*
Y1322748D01*
G01X1071925Y1320527D02*
G03X1072425Y1321027I0J500D01*
G01X1071925Y1319377D02*
G03X1073575Y1321027I0J1650D01*
G01X1066418Y1320527D02*
X1071925D01*
G01X1066611Y1319377D02*
X1071925D01*
G01X1056625Y1323775D02*
X1058043Y1324263D01*
G01X1052654Y1322408D02*
X1054072Y1322896D01*
G01X1056625Y1323775D02*
X1058043Y1324263D01*
G01X1052654Y1322408D02*
X1054072Y1322896D01*
G01X1073575Y1328114D02*
Y1329835D01*
G01X1072425Y1328114D02*
Y1329835D01*
G01X1071925Y1326464D02*
G03X1073575Y1328114I0J1650D01*
G01X1071925Y1327614D02*
G03X1072425Y1328114I0J500D01*
G01X1067968Y1326464D02*
X1071925D01*
G01X1067775Y1327614D02*
X1071925D01*
G01X1064568Y1326510D02*
X1067775Y1327614D01*
G01X1064567Y1326510D02*
X1064568D01*
G01X1060596Y1325142D02*
X1062014Y1325631D01*
G01X1072425Y1328114D02*
Y1329835D01*
G01X1073575Y1328114D02*
Y1329835D01*
G01X1071925Y1327614D02*
G03X1072425Y1328114I0J500D01*
G01X1071925Y1326464D02*
G03X1073575Y1328114I0J1650D01*
G01X1067775Y1327614D02*
X1071925D01*
G01X1067968Y1326464D02*
X1071925D01*
G01X1064568Y1326510D02*
X1067775Y1327614D01*
G01X1064567Y1326510D02*
X1064568D01*
G01X1060596Y1325142D02*
X1062014Y1325631D01*
G01X1073575Y1377720D02*
Y1379441D01*
G01X1072425Y1377720D02*
Y1379441D01*
G01X1071925Y1376070D02*
G03X1073575Y1377720I0J1650D01*
G01X1071925Y1377220D02*
G03X1072425Y1377720I0J500D01*
G01X1065445Y1376070D02*
X1071925D01*
G01X1065157Y1377220D02*
X1071925D01*
G01X1072425Y1377720D02*
Y1379441D01*
G01X1073575Y1377720D02*
Y1379441D01*
G01X1071925Y1377220D02*
G03X1072425Y1377720I0J500D01*
G01X1071925Y1376070D02*
G03X1073575Y1377720I0J1650D01*
G01X1065157Y1377220D02*
X1071925D01*
G01X1065445Y1376070D02*
X1071925D01*
G01X1073575Y1384555D02*
Y1386528D01*
G01X1072425Y1384555D02*
Y1386528D01*
G01X1071925Y1382905D02*
G03X1073575Y1384555I0J1650D01*
G01X1071925Y1384055D02*
G03X1072425Y1384555I0J500D01*
G01X1065210Y1382905D02*
X1071925D01*
G01X1064922Y1384055D02*
X1071925D01*
G01X1072425Y1384555D02*
Y1386528D01*
G01X1073575Y1384555D02*
Y1386528D01*
G01X1071925Y1384055D02*
G03X1072425Y1384555I0J500D01*
G01X1071925Y1382905D02*
G03X1073575Y1384555I0J1650D01*
G01X1064922Y1384055D02*
X1071925D01*
G01X1065210Y1382905D02*
X1071925D01*
G01X1073575Y1391893D02*
Y1393614D01*
G01X1072425Y1391893D02*
Y1393614D01*
G01X1071925Y1390243D02*
G03X1073575Y1391893I0J1650D01*
G01X1071925Y1391393D02*
G03X1072425Y1391893I0J500D01*
G01X1066092Y1390243D02*
X1071925D01*
G01X1065804Y1391393D02*
X1071925D01*
G01X1072425Y1391893D02*
Y1393614D01*
G01X1073575Y1391893D02*
Y1393614D01*
G01X1071925Y1391393D02*
G03X1072425Y1391893I0J500D01*
G01X1071925Y1390243D02*
G03X1073575Y1391893I0J1650D01*
G01X1065804Y1391393D02*
X1071925D01*
G01X1066092Y1390243D02*
X1071925D01*
G01X1073575Y1398980D02*
Y1400701D01*
G01X1072425Y1398980D02*
Y1400701D01*
G01X1071925Y1397330D02*
G03X1073575Y1398980I0J1650D01*
G01X1071925Y1398480D02*
G03X1072425Y1398980I0J500D01*
G01X1066392Y1397330D02*
X1071925D01*
G01X1066104Y1398480D02*
X1071925D01*
G01X1072425Y1398980D02*
Y1400701D01*
G01X1073575Y1398980D02*
Y1400701D01*
G01X1071925Y1398480D02*
G03X1072425Y1398980I0J500D01*
G01X1071925Y1397330D02*
G03X1073575Y1398980I0J1650D01*
G01X1066104Y1398480D02*
X1071925D01*
G01X1066392Y1397330D02*
X1071925D01*
G01X1073575Y1406055D02*
Y1407787D01*
G01X1072425Y1406055D02*
Y1407787D01*
G01X1071925Y1404405D02*
G03X1073575Y1406055I0J1650D01*
G01X1071925Y1405555D02*
G03X1072425Y1406055I0J500D01*
G01X1066737Y1404405D02*
X1071925D01*
G01X1066449Y1405555D02*
X1071925D01*
G01X1072425Y1406055D02*
Y1407787D01*
G01X1073575Y1406055D02*
Y1407787D01*
G01X1071925Y1405555D02*
G03X1072425Y1406055I0J500D01*
G01X1071925Y1404405D02*
G03X1073575Y1406055I0J1650D01*
G01X1066449Y1405555D02*
X1071925D01*
G01X1066737Y1404405D02*
X1071925D01*
G01X1073575Y1412558D02*
Y1414874D01*
G01X1072425Y1412558D02*
Y1414874D01*
G01X1071925Y1410908D02*
G03X1073575Y1412558I0J1650D01*
G01X1071925Y1412058D02*
G03X1072425Y1412558I0J500D01*
G01X1064724Y1410908D02*
X1071925D01*
G01X1064436Y1412058D02*
X1071925D01*
G01X1072425Y1412558D02*
Y1414874D01*
G01X1073575Y1412558D02*
Y1414874D01*
G01X1071925Y1412058D02*
G03X1072425Y1412558I0J500D01*
G01X1071925Y1410908D02*
G03X1073575Y1412558I0J1650D01*
G01X1064436Y1412058D02*
X1071925D01*
G01X1064724Y1410908D02*
X1071925D01*
G01X1259575Y171398D02*
Y168708D01*
G01X1258425Y171875D02*
Y168708D01*
G01X1260460Y172283D02*
X1259575Y171398D01*
G01X1259983Y173433D02*
X1258425Y171875D01*
G01X1263892Y172283D02*
X1260460D01*
G01X1263881Y173433D02*
X1259983D01*
G01X1258425Y171875D02*
Y168708D01*
G01X1259575Y171398D02*
Y168708D01*
G01X1259983Y173433D02*
X1258425Y171875D01*
G01X1260460Y172283D02*
X1259575Y171398D01*
G01X1263881Y173433D02*
X1259983D01*
G01X1263892Y172283D02*
X1260460D01*
G01X1272075Y185896D02*
X1274746Y188567D01*
G01X1273225Y185419D02*
X1275223Y187417D01*
G01X1272075Y183792D02*
Y185896D01*
G01X1273225Y183792D02*
Y185419D01*
G01X1274746Y188567D02*
X1282624D01*
G01X1275223Y187417D02*
X1282390D01*
G01X1272075Y185896D02*
X1274746Y188567D01*
G01X1273225Y185419D02*
X1275223Y187417D01*
G01X1272075Y183792D02*
Y185896D01*
G01X1273225Y183792D02*
Y185419D01*
G01X1274746Y188567D02*
X1282624D01*
G01X1275223Y187417D02*
X1282390D01*
G01X1273225Y185419D02*
X1275223Y187417D01*
G01X1272075Y185896D02*
X1274746Y188567D01*
G01X1273225Y183792D02*
Y185419D01*
G01X1272075Y183792D02*
Y185896D01*
G01X1275223Y187417D02*
X1282390D01*
G01X1274746Y188567D02*
X1282624D01*
G01X1273225Y185419D02*
X1275223Y187417D01*
G01X1272075Y185896D02*
X1274746Y188567D01*
G01X1273225Y183792D02*
Y185419D01*
G01X1272075Y183792D02*
Y185896D01*
G01X1275223Y187417D02*
X1282390D01*
G01X1274746Y188567D02*
X1282624D01*
G01X1269807Y172417D02*
X1282624D01*
G01X1269807Y173567D02*
X1282624D01*
G01X1269807Y172417D02*
X1282624D01*
G01X1269807Y173567D02*
X1282624D01*
G01X1269807D02*
X1282624D01*
G01X1269807Y172417D02*
X1282624D01*
G01X1269807Y173567D02*
X1282624D01*
G01X1269807Y172417D02*
X1282624D01*
G01X1260301Y625173D02*
X1263349D01*
G01X1260301Y626323D02*
X1263349D01*
G01X1260301D02*
X1263349D01*
G01X1260301Y625173D02*
X1263349D01*
G01X1279001Y641323D02*
X1282516D01*
G01X1279001Y640173D02*
X1282624D01*
G01X1279001D02*
X1282624D01*
G01X1279001Y641323D02*
X1282516D01*
G01X1269707Y625173D02*
X1282624D01*
G01X1269707Y626323D02*
X1282624D01*
G01X1269707D02*
X1282624D01*
G01X1269707Y625173D02*
X1282624D01*
G01X1260367Y1077929D02*
X1263349D01*
G01X1260368Y1079079D02*
X1263349D01*
G01X1260368D02*
X1263349D01*
G01X1260367Y1077929D02*
X1263349D01*
G01X1270007D02*
X1282624D01*
G01X1270007Y1079079D02*
X1282624D01*
G01X1270007D02*
X1282624D01*
G01X1270007Y1077929D02*
X1282624D01*
G01X1279001Y1094079D02*
X1282560D01*
G01X1279001Y1092929D02*
X1282624D01*
G01X1279001D02*
X1282624D01*
G01X1279001Y1094079D02*
X1282560D01*
G01X1383893Y171503D02*
Y168323D01*
G01X1382743Y171980D02*
Y168323D01*
G01X1384770Y172380D02*
X1383893Y171503D01*
G01X1384293Y173530D02*
X1382743Y171980D01*
G01X1386999Y172380D02*
X1384770D01*
G01X1386925Y173530D02*
X1384293D01*
G01X1382743Y171980D02*
Y168323D01*
G01X1383893Y171503D02*
Y168323D01*
G01X1384293Y173530D02*
X1382743Y171980D01*
G01X1384770Y172380D02*
X1383893Y171503D01*
G01X1386925Y173530D02*
X1384293D01*
G01X1386999Y172380D02*
X1384770D01*
G01X1403213Y188567D02*
X1406837D01*
G01X1403213Y187417D02*
X1406837D01*
G01X1403213D02*
X1406837D01*
G01X1403213Y188567D02*
X1406837D01*
G01X1393720Y172417D02*
X1406837D01*
G01X1393720Y173567D02*
X1406837D01*
G01X1393720D02*
X1406837D01*
G01X1393720Y172417D02*
X1406837D01*
G01X1384565Y625173D02*
X1387562D01*
G01X1384554Y626323D02*
X1387562D01*
G01X1384554D02*
X1387562D01*
G01X1384565Y625173D02*
X1387562D01*
G01X1403214Y641323D02*
X1406767D01*
G01X1403214Y640173D02*
X1406837D01*
G01X1403214D02*
X1406837D01*
G01X1403214Y641323D02*
X1406767D01*
G01X1394220Y625173D02*
X1406837D01*
G01X1394220Y626323D02*
X1406837D01*
G01X1394220D02*
X1406837D01*
G01X1394220Y625173D02*
X1406837D01*
G01X1384583Y1077929D02*
X1387562D01*
G01X1384582Y1079079D02*
X1387562D01*
G01X1384582D02*
X1387562D01*
G01X1384583Y1077929D02*
X1387562D01*
G01X1394320D02*
X1406837D01*
G01X1394320Y1079079D02*
X1406837D01*
G01X1394320D02*
X1406837D01*
G01X1394320Y1077929D02*
X1406837D01*
G01X1403214Y1094079D02*
X1406787D01*
G01X1403214Y1092929D02*
X1406837D01*
G01X1403214D02*
X1406837D01*
G01X1403214Y1094079D02*
X1406787D01*
G01X1509856Y172417D02*
X1511774D01*
G01X1510333Y173567D02*
X1511774D01*
G01X1508625Y173648D02*
X1509856Y172417D01*
G01X1509775Y174125D02*
X1510333Y173567D01*
G01X1508625Y181162D02*
Y173648D01*
G01X1509775Y181192D02*
Y174125D01*
G01X1510333Y173567D02*
X1511774D01*
G01X1509856Y172417D02*
X1511774D01*
G01X1509775Y174125D02*
X1510333Y173567D01*
G01X1508625Y173648D02*
X1509856Y172417D01*
G01X1509775Y181192D02*
Y174125D01*
G01X1508625Y181162D02*
Y173648D01*
G01X1518132Y172417D02*
X1531049D01*
G01X1518132Y173567D02*
X1531049D01*
G01X1518132D02*
X1531049D01*
G01X1518132Y172417D02*
X1531049D01*
G01X1508790Y625173D02*
X1511774D01*
G01X1508789Y626323D02*
X1511774D01*
G01X1508789D02*
X1511774D01*
G01X1508790Y625173D02*
X1511774D01*
G01X1517932D02*
X1531049D01*
G01X1517932Y626323D02*
X1531049D01*
G01X1517932D02*
X1531049D01*
G01X1517932Y625173D02*
X1531049D01*
G01X1508763Y1077929D02*
X1511774D01*
G01X1508782Y1079079D02*
X1511774D01*
G01X1508782D02*
X1511774D01*
G01X1508763Y1077929D02*
X1511774D01*
G01X1518232D02*
X1531049D01*
G01X1518232Y1079079D02*
X1531049D01*
G01X1518232D02*
X1531049D01*
G01X1518232Y1077929D02*
X1531049D01*
G01X1527426Y188567D02*
X1531049D01*
G01X1527426Y187417D02*
X1531049D01*
G01X1527426D02*
X1531049D01*
G01X1527426Y188567D02*
X1531049D01*
G01X1527426Y641323D02*
X1530945D01*
G01X1527426Y640173D02*
X1531049D01*
G01X1527426D02*
X1531049D01*
G01X1527426Y641323D02*
X1530945D01*
G01X1527426Y1094079D02*
X1530991D01*
G01X1527426Y1092929D02*
X1531049D01*
G01X1527426D02*
X1531049D01*
G01X1527426Y1094079D02*
X1530991D01*
G01X1632994Y172417D02*
X1635987D01*
G01X1633084Y173567D02*
X1635987D01*
G01X1633084D02*
X1635987D01*
G01X1632994Y172417D02*
X1635987D01*
G01X1651639Y188567D02*
X1655190D01*
G01X1651639Y187417D02*
X1655262D01*
G01X1651639D02*
X1655262D01*
G01X1651639Y188567D02*
X1655190D01*
G01X1642545Y172417D02*
X1655262D01*
G01X1642545Y173567D02*
X1655262D01*
G01X1642545D02*
X1655262D01*
G01X1642545Y172417D02*
X1655262D01*
G01X1632971Y625173D02*
X1635987D01*
G01X1633041Y626323D02*
X1635987D01*
G01X1633041D02*
X1635987D01*
G01X1632971Y625173D02*
X1635987D01*
G01X1651639Y641323D02*
X1655102D01*
G01X1651639Y640173D02*
X1655262D01*
G01X1651639D02*
X1655262D01*
G01X1651639Y641323D02*
X1655102D01*
G01X1642245Y625173D02*
X1655262D01*
G01X1642245Y626323D02*
X1655262D01*
G01X1642245D02*
X1655262D01*
G01X1642245Y625173D02*
X1655262D01*
G01X1632980Y1077929D02*
X1635987D01*
G01X1633036Y1079079D02*
X1635987D01*
G01X1633036D02*
X1635987D01*
G01X1632980Y1077929D02*
X1635987D01*
G01X1642745D02*
X1655262D01*
G01X1642745Y1079079D02*
X1655262D01*
G01X1642745D02*
X1655262D01*
G01X1642745Y1077929D02*
X1655262D01*
G01X1651639Y1094079D02*
X1655132D01*
G01X1651639Y1092929D02*
X1655262D01*
G01X1651639D02*
X1655262D01*
G01X1651639Y1094079D02*
X1655132D01*
G01X1757199Y172417D02*
X1760199D01*
G01X1757312Y173567D02*
X1760199D01*
G01X1757312D02*
X1760199D01*
G01X1757199Y172417D02*
X1760199D01*
G01X1735199Y625173D02*
X1732204D01*
G01X1735199Y626323D02*
X1732244D01*
G01X1735199D02*
X1732244D01*
G01X1735199Y625173D02*
X1732204D01*
G01X1779406Y641323D02*
X1725934D01*
G01X1779474Y640173D02*
X1725934D01*
G01X1779474D02*
X1725934D01*
G01X1779406Y641323D02*
X1725934D01*
G01X1779474Y625173D02*
X1741557D01*
G01X1779474Y626323D02*
X1741557D01*
G01X1779474D02*
X1741557D01*
G01X1779474Y625173D02*
X1741557D01*
G01X1757303Y1077929D02*
X1760199D01*
G01X1757248Y1079079D02*
X1760199D01*
G01X1757248D02*
X1760199D01*
G01X1757303Y1077929D02*
X1760199D01*
G01X1775980Y188567D02*
X1779418D01*
G01X1775980Y187417D02*
X1779474D01*
G01X1775980D02*
X1779474D01*
G01X1775980Y188567D02*
X1779418D01*
G01X1766757Y172417D02*
X1779474D01*
G01X1766757Y173567D02*
X1779474D01*
G01X1766757D02*
X1779474D01*
G01X1766757Y172417D02*
X1779474D01*
G01X1766657Y1077929D02*
X1779474D01*
G01X1766657Y1079079D02*
X1779474D01*
G01X1766657D02*
X1779474D01*
G01X1766657Y1077929D02*
X1779474D01*
G01X1775981Y1094079D02*
X1779336D01*
G01X1775981Y1092929D02*
X1779474D01*
G01X1775981D02*
X1779474D01*
G01X1775981Y1094079D02*
X1779336D01*
G01X1881409Y172417D02*
X1884412D01*
G01X1881470Y173567D02*
X1884412D01*
G01X1881470D02*
X1884412D01*
G01X1881409Y172417D02*
X1884412D01*
G01X1903655Y188567D02*
X1900176D01*
G01Y187417D02*
X1903687D01*
G01X1900176D02*
X1903687D01*
G01X1903655Y188567D02*
X1900176D01*
G01X1890970Y172417D02*
X1903687D01*
G01X1890970Y173567D02*
X1903687D01*
G01X1890970D02*
X1903687D01*
G01X1890970Y172417D02*
X1903687D01*
G01X1881474Y625173D02*
X1884412D01*
G01X1881402Y626323D02*
X1884412D01*
G01X1881402D02*
X1884412D01*
G01X1881474Y625173D02*
X1884412D01*
G01X1900231Y641323D02*
X1903549D01*
G01X1900231Y640173D02*
X1903687D01*
G01X1900231D02*
X1903687D01*
G01X1900231Y641323D02*
X1903549D01*
G01X1891270Y625173D02*
X1903687D01*
G01X1891270Y626323D02*
X1903687D01*
G01X1891270D02*
X1903687D01*
G01X1891270Y625173D02*
X1903687D01*
G01X1881411Y1077929D02*
X1884412D01*
G01X1881448Y1079079D02*
X1884412D01*
G01X1881448D02*
X1884412D01*
G01X1881411Y1077929D02*
X1884412D01*
G01X1891070D02*
X1903687D01*
G01X1891070Y1079079D02*
X1903687D01*
G01X1891070D02*
X1903687D01*
G01X1891070Y1077929D02*
X1903687D01*
G01X1900064Y1094079D02*
X1903595D01*
G01X1900064Y1092929D02*
X1903687D01*
G01X1900064D02*
X1903687D01*
G01X1900064Y1094079D02*
X1903595D01*
G54D12*
G01X6250Y-185556D02*
Y-203056D01*
G01X1228Y-185556D02*
X11272D01*
G01X20038Y-203056D02*
Y-185556D01*
G01Y-194014D02*
X21130Y-192556D01*
X22222Y-191681D01*
X23968Y-191390D01*
X25278Y-191681D01*
X26807Y-192848D01*
X27462Y-194598D01*
Y-203056D01*
G01X41250Y-191390D02*
Y-203056D01*
G01Y-186723D02*
X40813Y-186431D01*
Y-185848D01*
X41250Y-185556D01*
X41687Y-185848D01*
Y-186431D01*
X41250Y-186723D01*
G01X55475Y-201015D02*
X56567Y-202181D01*
X58095Y-203056D01*
X59405D01*
X60715Y-202473D01*
X61588Y-201598D01*
X62025Y-200432D01*
X61807Y-198681D01*
X60933Y-197806D01*
X57003Y-196056D01*
X56130Y-194014D01*
X56567Y-192556D01*
X57440Y-191681D01*
X58750Y-191390D01*
X60060Y-191681D01*
X61370Y-192556D01*
G01X90693Y-207431D02*
X92222Y-208598D01*
X93968Y-208889D01*
X95496Y-208598D01*
X96807Y-207140D01*
X97680Y-205098D01*
Y-191390D01*
G01Y-193723D02*
X96807Y-192556D01*
X95496Y-191681D01*
X93968Y-191390D01*
X92222Y-191973D01*
X91130Y-193139D01*
X90256Y-195181D01*
X89820Y-197223D01*
X90038Y-198973D01*
X90912Y-201015D01*
X92222Y-202473D01*
X93968Y-203056D01*
X95278Y-202764D01*
X96807Y-201598D01*
X97680Y-200432D01*
G01X107975Y-195181D02*
X114962D01*
X114307Y-193139D01*
X113215Y-191973D01*
X111687Y-191390D01*
X110158Y-191681D01*
X108848Y-192556D01*
X107975Y-194598D01*
X107538Y-196348D01*
Y-198098D01*
X107975Y-199848D01*
X109067Y-201598D01*
X110377Y-202764D01*
X111905Y-203056D01*
X113433Y-202473D01*
X114962Y-200723D01*
G01X125693Y-203056D02*
Y-191390D01*
G01Y-193723D02*
X126785Y-192556D01*
X127877Y-191681D01*
X129405Y-191390D01*
X130496Y-191681D01*
X131807Y-192556D01*
G01X142320Y-203056D02*
Y-185556D01*
G01Y-194306D02*
X143412Y-192556D01*
X144722Y-191681D01*
X146032Y-191390D01*
X147996Y-191973D01*
X149307Y-193139D01*
X150180Y-195181D01*
Y-197514D01*
X149743Y-199848D01*
X148870Y-201598D01*
X147342Y-202764D01*
X146032Y-203056D01*
X144722Y-202764D01*
X143412Y-201890D01*
X142320Y-200432D01*
G01X160475Y-195181D02*
X167462D01*
X166807Y-193139D01*
X165715Y-191973D01*
X164187Y-191390D01*
X162658Y-191681D01*
X161348Y-192556D01*
X160475Y-194598D01*
X160038Y-196348D01*
Y-198098D01*
X160475Y-199848D01*
X161567Y-201598D01*
X162877Y-202764D01*
X164405Y-203056D01*
X165933Y-202473D01*
X167462Y-200723D01*
G01X178193Y-203056D02*
Y-191390D01*
G01Y-193723D02*
X179285Y-192556D01*
X180377Y-191681D01*
X181905Y-191390D01*
X182996Y-191681D01*
X184307Y-192556D01*
G01X216250Y-191390D02*
Y-203056D01*
G01Y-186723D02*
X215813Y-186431D01*
Y-185848D01*
X216250Y-185556D01*
X216687Y-185848D01*
Y-186431D01*
X216250Y-186723D01*
G01X230475Y-201015D02*
X231567Y-202181D01*
X233095Y-203056D01*
X234405D01*
X235715Y-202473D01*
X236588Y-201598D01*
X237025Y-200432D01*
X236807Y-198681D01*
X235933Y-197806D01*
X232003Y-196056D01*
X231130Y-194014D01*
X231567Y-192556D01*
X232440Y-191681D01*
X233750Y-191390D01*
X235060Y-191681D01*
X236370Y-192556D01*
G01X265256Y-207431D02*
X266785Y-208598D01*
X268095Y-208889D01*
X269842Y-208306D01*
X271152Y-206848D01*
X271807Y-204222D01*
Y-191390D01*
G01Y-186723D02*
X271370Y-186431D01*
Y-185848D01*
X271807Y-185556D01*
X272243Y-185848D01*
Y-186431D01*
X271807Y-186723D01*
G01X282538Y-191390D02*
Y-199556D01*
X283412Y-201598D01*
X284722Y-202764D01*
X286250Y-203056D01*
X287778Y-202764D01*
X289088Y-201598D01*
X289962Y-199556D01*
G01Y-203056D02*
Y-191390D01*
G01X300475Y-201015D02*
X301567Y-202181D01*
X303095Y-203056D01*
X304405D01*
X305715Y-202473D01*
X306588Y-201598D01*
X307025Y-200432D01*
X306807Y-198681D01*
X305933Y-197806D01*
X302003Y-196056D01*
X301130Y-194014D01*
X301567Y-192556D01*
X302440Y-191681D01*
X303750Y-191390D01*
X305060Y-191681D01*
X306370Y-192556D01*
G01X321250Y-185556D02*
Y-203056D01*
G01X318193Y-191390D02*
X324307D01*
G01X354940Y-203056D02*
Y-188181D01*
X355377Y-186723D01*
X356250Y-185848D01*
X357560Y-185556D01*
X358870Y-186139D01*
X359525Y-187598D01*
G01X356905Y-192556D02*
X352538D01*
G01X373750Y-203056D02*
X372440Y-202764D01*
X371130Y-201598D01*
X370256Y-199556D01*
X369820Y-197223D01*
X370256Y-194889D01*
X371130Y-192848D01*
X372440Y-191681D01*
X373750Y-191390D01*
X375060Y-191681D01*
X376370Y-192848D01*
X377243Y-194889D01*
X377462Y-197223D01*
X377243Y-199556D01*
X376370Y-201598D01*
X375060Y-202764D01*
X373750Y-203056D01*
G01X388193D02*
Y-191390D01*
G01Y-193723D02*
X389285Y-192556D01*
X390377Y-191681D01*
X391905Y-191390D01*
X392996Y-191681D01*
X394307Y-192556D01*
G01X421665Y-208306D02*
X422975Y-208889D01*
X424722Y-208306D01*
X425813Y-207140D01*
X426687Y-205681D01*
X427996Y-201015D01*
X430835Y-191390D01*
G01X423848D02*
X427996Y-201015D01*
G01X443750Y-203056D02*
X442440Y-202764D01*
X441130Y-201598D01*
X440256Y-199556D01*
X439820Y-197223D01*
X440256Y-194889D01*
X441130Y-192848D01*
X442440Y-191681D01*
X443750Y-191390D01*
X445060Y-191681D01*
X446370Y-192848D01*
X447243Y-194889D01*
X447462Y-197223D01*
X447243Y-199556D01*
X446370Y-201598D01*
X445060Y-202764D01*
X443750Y-203056D01*
G01X457538Y-191390D02*
Y-199556D01*
X458412Y-201598D01*
X459722Y-202764D01*
X461250Y-203056D01*
X462778Y-202764D01*
X464088Y-201598D01*
X464962Y-199556D01*
G01Y-203056D02*
Y-191390D01*
G01X475693Y-203056D02*
Y-191390D01*
G01Y-193723D02*
X476785Y-192556D01*
X477877Y-191681D01*
X479405Y-191390D01*
X480496Y-191681D01*
X481807Y-192556D01*
G01X510693Y-203056D02*
Y-191390D01*
G01Y-193723D02*
X511785Y-192556D01*
X512877Y-191681D01*
X514405Y-191390D01*
X515496Y-191681D01*
X516807Y-192556D01*
G01X527975Y-195181D02*
X534962D01*
X534307Y-193139D01*
X533215Y-191973D01*
X531687Y-191390D01*
X530158Y-191681D01*
X528848Y-192556D01*
X527975Y-194598D01*
X527538Y-196348D01*
Y-198098D01*
X527975Y-199848D01*
X529067Y-201598D01*
X530377Y-202764D01*
X531905Y-203056D01*
X533433Y-202473D01*
X534962Y-200723D01*
G01X547440Y-203056D02*
Y-188181D01*
X547877Y-186723D01*
X548750Y-185848D01*
X550060Y-185556D01*
X551370Y-186139D01*
X552025Y-187598D01*
G01X549405Y-192556D02*
X545038D01*
G01X562975Y-195181D02*
X569962D01*
X569307Y-193139D01*
X568215Y-191973D01*
X566687Y-191390D01*
X565158Y-191681D01*
X563848Y-192556D01*
X562975Y-194598D01*
X562538Y-196348D01*
Y-198098D01*
X562975Y-199848D01*
X564067Y-201598D01*
X565377Y-202764D01*
X566905Y-203056D01*
X568433Y-202473D01*
X569962Y-200723D01*
G01X580693Y-203056D02*
Y-191390D01*
G01Y-193723D02*
X581785Y-192556D01*
X582877Y-191681D01*
X584405Y-191390D01*
X585496Y-191681D01*
X586807Y-192556D01*
G01X597975Y-195181D02*
X604962D01*
X604307Y-193139D01*
X603215Y-191973D01*
X601687Y-191390D01*
X600158Y-191681D01*
X598848Y-192556D01*
X597975Y-194598D01*
X597538Y-196348D01*
Y-198098D01*
X597975Y-199848D01*
X599067Y-201598D01*
X600377Y-202764D01*
X601905Y-203056D01*
X603433Y-202473D01*
X604962Y-200723D01*
G01X615038Y-203056D02*
Y-191390D01*
G01Y-194306D02*
X615912Y-192848D01*
X617222Y-191681D01*
X618968Y-191390D01*
X620496Y-191681D01*
X621807Y-192848D01*
X622462Y-194889D01*
Y-203056D01*
G01X639743Y-192848D02*
X638215Y-191681D01*
X636905Y-191390D01*
X635158Y-191973D01*
X633848Y-193139D01*
X632975Y-195181D01*
X632756Y-197223D01*
X632975Y-199265D01*
X633848Y-201015D01*
X635158Y-202473D01*
X636905Y-203056D01*
X638433Y-202473D01*
X639743Y-201306D01*
G01X650475Y-195181D02*
X657462D01*
X656807Y-193139D01*
X655715Y-191973D01*
X654187Y-191390D01*
X652658Y-191681D01*
X651348Y-192556D01*
X650475Y-194598D01*
X650038Y-196348D01*
Y-198098D01*
X650475Y-199848D01*
X651567Y-201598D01*
X652877Y-202764D01*
X654405Y-203056D01*
X655933Y-202473D01*
X657462Y-200723D01*
G01X688750Y-185556D02*
Y-203056D01*
G01X685693Y-191390D02*
X691807D01*
G01X706250Y-203056D02*
X704940Y-202764D01*
X703630Y-201598D01*
X702756Y-199556D01*
X702320Y-197223D01*
X702756Y-194889D01*
X703630Y-192848D01*
X704940Y-191681D01*
X706250Y-191390D01*
X707560Y-191681D01*
X708870Y-192848D01*
X709743Y-194889D01*
X709962Y-197223D01*
X709743Y-199556D01*
X708870Y-201598D01*
X707560Y-202764D01*
X706250Y-203056D01*
G01X739940D02*
Y-188181D01*
X740377Y-186723D01*
X741250Y-185848D01*
X742560Y-185556D01*
X743870Y-186139D01*
X744525Y-187598D01*
G01X741905Y-192556D02*
X737538D01*
G01X758750Y-191390D02*
Y-203056D01*
G01Y-186723D02*
X758313Y-186431D01*
Y-185848D01*
X758750Y-185556D01*
X759187Y-185848D01*
Y-186431D01*
X758750Y-186723D01*
G01X772538Y-203056D02*
Y-191390D01*
G01Y-194306D02*
X773412Y-192848D01*
X774722Y-191681D01*
X776468Y-191390D01*
X777996Y-191681D01*
X779307Y-192848D01*
X779962Y-194889D01*
Y-203056D01*
G01X797680Y-185556D02*
Y-203056D01*
G01Y-200432D02*
X796807Y-201890D01*
X795496Y-202764D01*
X793968Y-203056D01*
X792222Y-202473D01*
X790912Y-201015D01*
X790038Y-199265D01*
X789820Y-197223D01*
X790038Y-195181D01*
X790912Y-193431D01*
X792222Y-191973D01*
X793968Y-191390D01*
X795496Y-191681D01*
X796588Y-192265D01*
X797680Y-193431D01*
G01X828750Y-185556D02*
Y-203056D01*
G01X825693Y-191390D02*
X831807D01*
G01X842538Y-203056D02*
Y-185556D01*
G01Y-194014D02*
X843630Y-192556D01*
X844722Y-191681D01*
X846468Y-191390D01*
X847778Y-191681D01*
X849307Y-192848D01*
X849962Y-194598D01*
Y-203056D01*
G01X860475Y-195181D02*
X867462D01*
X866807Y-193139D01*
X865715Y-191973D01*
X864187Y-191390D01*
X862658Y-191681D01*
X861348Y-192556D01*
X860475Y-194598D01*
X860038Y-196348D01*
Y-198098D01*
X860475Y-199848D01*
X861567Y-201598D01*
X862877Y-202764D01*
X864405Y-203056D01*
X865933Y-202473D01*
X867462Y-200723D01*
G01X893947Y-203056D02*
Y-185556D01*
X898313D01*
X900060Y-186431D01*
X901370Y-187598D01*
X902462Y-189347D01*
X903335Y-191390D01*
X903553Y-194306D01*
X903335Y-197223D01*
X902462Y-199265D01*
X901370Y-201015D01*
X900060Y-202181D01*
X898313Y-203056D01*
X893947D01*
G01X911883D02*
Y-185556D01*
X917123D01*
X918870Y-186431D01*
X920180Y-188473D01*
X920617Y-190806D01*
X920180Y-193139D01*
X919088Y-194889D01*
X917123Y-195765D01*
X911883D01*
G01X951250Y-191390D02*
Y-203056D01*
G01Y-186723D02*
X950813Y-186431D01*
Y-185848D01*
X951250Y-185556D01*
X951687Y-185848D01*
Y-186431D01*
X951250Y-186723D01*
G01X962200Y-203056D02*
Y-191390D01*
G01Y-194598D02*
X962855Y-193139D01*
X963947Y-191973D01*
X965475Y-191390D01*
X967003Y-191973D01*
X968095Y-193139D01*
X968750Y-194598D01*
Y-203056D01*
G01Y-194598D02*
X969405Y-193139D01*
X970496Y-191973D01*
X972025Y-191390D01*
X973553Y-191973D01*
X974645Y-193139D01*
X975300Y-194889D01*
Y-203056D01*
G01X982320Y-208889D02*
Y-191390D01*
G01Y-194014D02*
X983412Y-192556D01*
X984503Y-191681D01*
X986250Y-191390D01*
X987778Y-191681D01*
X989307Y-193139D01*
X989962Y-195181D01*
X990180Y-197223D01*
X989962Y-199265D01*
X989307Y-201306D01*
X987996Y-202473D01*
X986250Y-203056D01*
X984722Y-202764D01*
X983193Y-201890D01*
X982320Y-200723D01*
G01X1000475Y-195181D02*
X1007462D01*
X1006807Y-193139D01*
X1005715Y-191973D01*
X1004187Y-191390D01*
X1002658Y-191681D01*
X1001348Y-192556D01*
X1000475Y-194598D01*
X1000038Y-196348D01*
Y-198098D01*
X1000475Y-199848D01*
X1001567Y-201598D01*
X1002877Y-202764D01*
X1004405Y-203056D01*
X1005933Y-202473D01*
X1007462Y-200723D01*
G01X1025180Y-185556D02*
Y-203056D01*
G01Y-200432D02*
X1024307Y-201890D01*
X1022996Y-202764D01*
X1021468Y-203056D01*
X1019722Y-202473D01*
X1018412Y-201015D01*
X1017538Y-199265D01*
X1017320Y-197223D01*
X1017538Y-195181D01*
X1018412Y-193431D01*
X1019722Y-191973D01*
X1021468Y-191390D01*
X1022996Y-191681D01*
X1024088Y-192265D01*
X1025180Y-193431D01*
G01X1042680Y-203056D02*
Y-191390D01*
G01Y-193431D02*
X1041807Y-192265D01*
X1040496Y-191681D01*
X1038968Y-191390D01*
X1037440Y-191973D01*
X1036130Y-193139D01*
X1035256Y-194889D01*
X1034820Y-197223D01*
X1035256Y-199556D01*
X1036130Y-201306D01*
X1037440Y-202473D01*
X1038968Y-203056D01*
X1040496Y-202764D01*
X1041807Y-201890D01*
X1042680Y-200723D01*
G01X1052538Y-203056D02*
Y-191390D01*
G01Y-194306D02*
X1053412Y-192848D01*
X1054722Y-191681D01*
X1056468Y-191390D01*
X1057996Y-191681D01*
X1059307Y-192848D01*
X1059962Y-194889D01*
Y-203056D01*
G01X1077243Y-192848D02*
X1075715Y-191681D01*
X1074405Y-191390D01*
X1072658Y-191973D01*
X1071348Y-193139D01*
X1070475Y-195181D01*
X1070256Y-197223D01*
X1070475Y-199265D01*
X1071348Y-201015D01*
X1072658Y-202473D01*
X1074405Y-203056D01*
X1075933Y-202473D01*
X1077243Y-201306D01*
G01X1087975Y-195181D02*
X1094962D01*
X1094307Y-193139D01*
X1093215Y-191973D01*
X1091687Y-191390D01*
X1090158Y-191681D01*
X1088848Y-192556D01*
X1087975Y-194598D01*
X1087538Y-196348D01*
Y-198098D01*
X1087975Y-199848D01*
X1089067Y-201598D01*
X1090377Y-202764D01*
X1091905Y-203056D01*
X1093433Y-202473D01*
X1094962Y-200723D01*
G01X1126250Y-185556D02*
Y-203056D01*
G01X1123193Y-191390D02*
X1129307D01*
G01X1140693Y-203056D02*
Y-191390D01*
G01Y-193723D02*
X1141785Y-192556D01*
X1142877Y-191681D01*
X1144405Y-191390D01*
X1145496Y-191681D01*
X1146807Y-192556D01*
G01X1165180Y-203056D02*
Y-191390D01*
G01Y-193431D02*
X1164307Y-192265D01*
X1162996Y-191681D01*
X1161468Y-191390D01*
X1159940Y-191973D01*
X1158630Y-193139D01*
X1157756Y-194889D01*
X1157320Y-197223D01*
X1157756Y-199556D01*
X1158630Y-201306D01*
X1159940Y-202473D01*
X1161468Y-203056D01*
X1162996Y-202764D01*
X1164307Y-201890D01*
X1165180Y-200723D01*
G01X1182243Y-192848D02*
X1180715Y-191681D01*
X1179405Y-191390D01*
X1177658Y-191973D01*
X1176348Y-193139D01*
X1175475Y-195181D01*
X1175256Y-197223D01*
X1175475Y-199265D01*
X1176348Y-201015D01*
X1177658Y-202473D01*
X1179405Y-203056D01*
X1180933Y-202473D01*
X1182243Y-201306D01*
G01X1192975Y-195181D02*
X1199962D01*
X1199307Y-193139D01*
X1198215Y-191973D01*
X1196687Y-191390D01*
X1195158Y-191681D01*
X1193848Y-192556D01*
X1192975Y-194598D01*
X1192538Y-196348D01*
Y-198098D01*
X1192975Y-199848D01*
X1194067Y-201598D01*
X1195377Y-202764D01*
X1196905Y-203056D01*
X1198433Y-202473D01*
X1199962Y-200723D01*
G01X1210475Y-201015D02*
X1211567Y-202181D01*
X1213095Y-203056D01*
X1214405D01*
X1215715Y-202473D01*
X1216588Y-201598D01*
X1217025Y-200432D01*
X1216807Y-198681D01*
X1215933Y-197806D01*
X1212003Y-196056D01*
X1211130Y-194014D01*
X1211567Y-192556D01*
X1212440Y-191681D01*
X1213750Y-191390D01*
X1215060Y-191681D01*
X1216370Y-192556D01*
G01X1248750Y-191390D02*
Y-203056D01*
G01Y-186723D02*
X1248313Y-186431D01*
Y-185848D01*
X1248750Y-185556D01*
X1249187Y-185848D01*
Y-186431D01*
X1248750Y-186723D01*
G01X1262538Y-203056D02*
Y-191390D01*
G01Y-194306D02*
X1263412Y-192848D01*
X1264722Y-191681D01*
X1266468Y-191390D01*
X1267996Y-191681D01*
X1269307Y-192848D01*
X1269962Y-194889D01*
Y-203056D01*
G01X1301250D02*
Y-185556D01*
G01X1322680Y-203056D02*
Y-191390D01*
G01Y-193431D02*
X1321807Y-192265D01*
X1320496Y-191681D01*
X1318968Y-191390D01*
X1317440Y-191973D01*
X1316130Y-193139D01*
X1315256Y-194889D01*
X1314820Y-197223D01*
X1315256Y-199556D01*
X1316130Y-201306D01*
X1317440Y-202473D01*
X1318968Y-203056D01*
X1320496Y-202764D01*
X1321807Y-201890D01*
X1322680Y-200723D01*
G01X1331665Y-208306D02*
X1332975Y-208889D01*
X1334722Y-208306D01*
X1335813Y-207140D01*
X1336687Y-205681D01*
X1337996Y-201015D01*
X1340835Y-191390D01*
G01X1333848D02*
X1337996Y-201015D01*
G01X1350475Y-195181D02*
X1357462D01*
X1356807Y-193139D01*
X1355715Y-191973D01*
X1354187Y-191390D01*
X1352658Y-191681D01*
X1351348Y-192556D01*
X1350475Y-194598D01*
X1350038Y-196348D01*
Y-198098D01*
X1350475Y-199848D01*
X1351567Y-201598D01*
X1352877Y-202764D01*
X1354405Y-203056D01*
X1355933Y-202473D01*
X1357462Y-200723D01*
G01X1368193Y-203056D02*
Y-191390D01*
G01Y-193723D02*
X1369285Y-192556D01*
X1370377Y-191681D01*
X1371905Y-191390D01*
X1372996Y-191681D01*
X1374307Y-192556D01*
G01X1401883Y-185556D02*
Y-203056D01*
X1410617D01*
G01X1423750D02*
Y-185556D01*
X1421130Y-189056D01*
G01Y-203056D02*
X1426370D01*
G01X1441250Y-203639D02*
X1440813Y-203348D01*
Y-202764D01*
X1441250Y-202473D01*
X1441687Y-202764D01*
Y-203348D01*
X1441250Y-203639D01*
G01X2008773Y1616518D02*
X2014013D01*
G01X2011393D02*
Y1599018D01*
G01X2008773D02*
X2014013D01*
G01X2023216D02*
Y1616518D01*
X2028893Y1601935D01*
X2034570Y1616518D01*
Y1599018D01*
G01X2042026D02*
Y1616518D01*
X2047266D01*
X2049013Y1615643D01*
X2050323Y1613601D01*
X2050760Y1611268D01*
X2050323Y1608935D01*
X2049231Y1607185D01*
X2047266Y1606309D01*
X2042026D01*
G01X2062801Y1593185D02*
X2060618Y1596101D01*
X2059526Y1599018D01*
Y1610684D01*
X2060618Y1613601D01*
X2062801Y1616518D01*
G01X2081393Y1599018D02*
X2079646Y1599310D01*
X2078118Y1600476D01*
X2076808Y1602226D01*
X2075934Y1604268D01*
X2075498Y1606601D01*
Y1608935D01*
X2075934Y1611268D01*
X2076808Y1613310D01*
X2078118Y1615059D01*
X2079646Y1616226D01*
X2081393Y1616518D01*
X2083139Y1616226D01*
X2084668Y1615059D01*
X2085978Y1613310D01*
X2086852Y1611268D01*
X2087288Y1608935D01*
Y1606601D01*
X2086852Y1604268D01*
X2085978Y1602226D01*
X2084668Y1600476D01*
X2083139Y1599310D01*
X2081393Y1599018D01*
G01X2095181D02*
Y1616518D01*
G01Y1608060D02*
X2096273Y1609518D01*
X2097365Y1610393D01*
X2099111Y1610684D01*
X2100421Y1610393D01*
X2101950Y1609226D01*
X2102605Y1607476D01*
Y1599018D01*
G01X2109843D02*
Y1610684D01*
G01Y1607476D02*
X2110498Y1608935D01*
X2111590Y1610101D01*
X2113118Y1610684D01*
X2114646Y1610101D01*
X2115738Y1608935D01*
X2116393Y1607476D01*
Y1599018D01*
G01Y1607476D02*
X2117048Y1608935D01*
X2118139Y1610101D01*
X2119668Y1610684D01*
X2121196Y1610101D01*
X2122288Y1608935D01*
X2122943Y1607185D01*
Y1599018D01*
G01X2134985Y1593185D02*
X2137168Y1596101D01*
X2138260Y1599018D01*
Y1610684D01*
X2137168Y1613601D01*
X2134985Y1616518D01*
G01X1986890Y1633668D02*
Y1651168D01*
X1991256D01*
X1993003Y1650293D01*
X1994313Y1649126D01*
X1995405Y1647377D01*
X1996278Y1645334D01*
X1996496Y1642418D01*
X1996278Y1639501D01*
X1995405Y1637459D01*
X1994313Y1635709D01*
X1993003Y1634543D01*
X1991256Y1633668D01*
X1986890D01*
G01X2004826D02*
Y1651168D01*
X2010066D01*
X2011813Y1650293D01*
X2013123Y1648251D01*
X2013560Y1645918D01*
X2013123Y1643585D01*
X2012031Y1641835D01*
X2010066Y1640959D01*
X2004826D01*
G01X2041573Y1651168D02*
X2046813D01*
G01X2044193D02*
Y1633668D01*
G01X2041573D02*
X2046813D01*
G01X2056016D02*
Y1651168D01*
X2061693Y1636585D01*
X2067370Y1651168D01*
Y1633668D01*
G01X2074826D02*
Y1651168D01*
X2080066D01*
X2081813Y1650293D01*
X2083123Y1648251D01*
X2083560Y1645918D01*
X2083123Y1643585D01*
X2082031Y1641835D01*
X2080066Y1640959D01*
X2074826D01*
G01X2101060Y1633668D02*
X2092326D01*
Y1651168D01*
X2101060D01*
G01X2097566Y1642710D02*
X2092326D01*
G01X2109390Y1633668D02*
Y1651168D01*
X2113756D01*
X2115503Y1650293D01*
X2116813Y1649126D01*
X2117905Y1647377D01*
X2118778Y1645334D01*
X2118996Y1642418D01*
X2118778Y1639501D01*
X2117905Y1637459D01*
X2116813Y1635709D01*
X2115503Y1634543D01*
X2113756Y1633668D01*
X2109390D01*
G01X2126234D02*
X2131693Y1651168D01*
X2137152Y1633668D01*
G01X2135186Y1639793D02*
X2128199D01*
G01X2144171Y1633668D02*
Y1651168D01*
X2154215Y1633668D01*
Y1651168D01*
G01X2171496Y1649709D02*
X2170186Y1650585D01*
X2168658Y1651168D01*
X2166911D01*
X2164946Y1650293D01*
X2163418Y1648835D01*
X2162326Y1647084D01*
X2161453Y1644168D01*
X2161234Y1641543D01*
X2161671Y1638918D01*
X2162326Y1637168D01*
X2163636Y1635418D01*
X2165165Y1634251D01*
X2166693Y1633668D01*
X2168221D01*
X2169750Y1634251D01*
X2171060Y1635126D01*
X2172152Y1636292D01*
G01X2188560Y1633668D02*
X2179826D01*
Y1651168D01*
X2188560D01*
G01X2185066Y1642710D02*
X2179826D01*
G01X2219193Y1651168D02*
Y1633668D01*
G01X2214171Y1651168D02*
X2224215D01*
G01X2231234Y1633668D02*
X2236693Y1651168D01*
X2242152Y1633668D01*
G01X2240186Y1639793D02*
X2233199D01*
G01X2255939Y1643001D02*
X2256813Y1643876D01*
X2257468Y1645334D01*
X2257905Y1647377D01*
X2257468Y1649126D01*
X2256595Y1650293D01*
X2255066Y1651168D01*
X2249171D01*
Y1633668D01*
X2256376D01*
X2257905Y1634834D01*
X2258778Y1636585D01*
X2259215Y1638626D01*
X2258778Y1640668D01*
X2257468Y1642418D01*
X2255939Y1643001D01*
X2249171D01*
G01X2267326Y1651168D02*
Y1633668D01*
X2276060D01*
G01X2293560D02*
X2284826D01*
Y1651168D01*
X2293560D01*
G01X2290066Y1642710D02*
X2284826D01*
G01X2306693Y1633085D02*
X2306256Y1633376D01*
Y1633960D01*
X2306693Y1634251D01*
X2307130Y1633960D01*
Y1633376D01*
X2306693Y1633085D01*
G01Y1640959D02*
X2306256Y1641251D01*
Y1641835D01*
X2306693Y1642126D01*
X2307130Y1641835D01*
Y1641251D01*
X2306693Y1640959D01*
G01X2337326Y1651168D02*
Y1633668D01*
X2346060D01*
G01X2359193D02*
Y1651168D01*
X2356573Y1647668D01*
G01Y1633668D02*
X2361813D01*
G01X2046393Y1564368D02*
X2047921Y1564660D01*
X2049668Y1565534D01*
X2050760Y1566992D01*
X2051196Y1569035D01*
X2050760Y1571076D01*
X2049450Y1572826D01*
X2047485Y1573701D01*
X2045301D01*
X2043991Y1574285D01*
X2042899Y1575743D01*
X2042463Y1577784D01*
X2043118Y1579826D01*
X2044646Y1581285D01*
X2046393Y1581868D01*
X2048139Y1581285D01*
X2049668Y1579826D01*
X2050323Y1577784D01*
X2049886Y1575743D01*
X2048795Y1574285D01*
X2047485Y1573701D01*
X2045301D01*
X2043336Y1572826D01*
X2042026Y1571076D01*
X2041590Y1569035D01*
X2042026Y1566992D01*
X2043118Y1565534D01*
X2044865Y1564660D01*
X2046393Y1564368D01*
G01X2059090Y1566992D02*
X2060399Y1565534D01*
X2061928Y1564660D01*
X2063893Y1564368D01*
X2065858Y1564951D01*
X2067386Y1566118D01*
X2068478Y1568159D01*
X2068696Y1570493D01*
X2068260Y1572826D01*
X2067168Y1574285D01*
X2065639Y1575451D01*
X2064111Y1575743D01*
X2062583Y1575451D01*
X2060618Y1574285D01*
X2061273Y1581868D01*
X2067168D01*
G01X2081393Y1563785D02*
X2080956Y1564076D01*
Y1564660D01*
X2081393Y1564951D01*
X2081830Y1564660D01*
Y1564076D01*
X2081393Y1563785D01*
G01X2098893Y1581868D02*
X2097146Y1581285D01*
X2095836Y1579826D01*
X2094963Y1578077D01*
X2094308Y1575743D01*
X2094090Y1573118D01*
X2094308Y1570493D01*
X2094963Y1568159D01*
X2095836Y1566409D01*
X2097146Y1564951D01*
X2098893Y1564368D01*
X2100639Y1564951D01*
X2101950Y1566409D01*
X2102823Y1568159D01*
X2103478Y1570493D01*
X2103696Y1573118D01*
X2103478Y1575743D01*
X2102823Y1578077D01*
X2101950Y1579826D01*
X2100639Y1581285D01*
X2098893Y1581868D01*
G01X2037643Y1529718D02*
Y1547218D01*
X2035023Y1543718D01*
G01Y1529718D02*
X2040263D01*
G01X2055143Y1547218D02*
X2053396Y1546635D01*
X2052086Y1545176D01*
X2051213Y1543427D01*
X2050558Y1541093D01*
X2050340Y1538468D01*
X2050558Y1535843D01*
X2051213Y1533509D01*
X2052086Y1531759D01*
X2053396Y1530301D01*
X2055143Y1529718D01*
X2056889Y1530301D01*
X2058200Y1531759D01*
X2059073Y1533509D01*
X2059728Y1535843D01*
X2059946Y1538468D01*
X2059728Y1541093D01*
X2059073Y1543427D01*
X2058200Y1545176D01*
X2056889Y1546635D01*
X2055143Y1547218D01*
G01X2072643D02*
X2070896Y1546635D01*
X2069586Y1545176D01*
X2068713Y1543427D01*
X2068058Y1541093D01*
X2067840Y1538468D01*
X2068058Y1535843D01*
X2068713Y1533509D01*
X2069586Y1531759D01*
X2070896Y1530301D01*
X2072643Y1529718D01*
X2074389Y1530301D01*
X2075700Y1531759D01*
X2076573Y1533509D01*
X2077228Y1535843D01*
X2077446Y1538468D01*
X2077228Y1541093D01*
X2076573Y1543427D01*
X2075700Y1545176D01*
X2074389Y1546635D01*
X2072643Y1547218D01*
G01X2090143Y1529135D02*
X2089706Y1529426D01*
Y1530010D01*
X2090143Y1530301D01*
X2090580Y1530010D01*
Y1529426D01*
X2090143Y1529135D01*
G01X2107643Y1547218D02*
X2105896Y1546635D01*
X2104586Y1545176D01*
X2103713Y1543427D01*
X2103058Y1541093D01*
X2102840Y1538468D01*
X2103058Y1535843D01*
X2103713Y1533509D01*
X2104586Y1531759D01*
X2105896Y1530301D01*
X2107643Y1529718D01*
X2109389Y1530301D01*
X2110700Y1531759D01*
X2111573Y1533509D01*
X2112228Y1535843D01*
X2112446Y1538468D01*
X2112228Y1541093D01*
X2111573Y1543427D01*
X2110700Y1545176D01*
X2109389Y1546635D01*
X2107643Y1547218D01*
G01X2188593Y1616518D02*
X2191649Y1599018D01*
X2195143Y1616518D01*
X2198636Y1599018D01*
X2201693Y1616518D01*
G01X2210023D02*
X2215263D01*
G01X2212643D02*
Y1599018D01*
G01X2210023D02*
X2215263D01*
G01X2225340D02*
Y1616518D01*
X2229706D01*
X2231453Y1615643D01*
X2232763Y1614476D01*
X2233855Y1612727D01*
X2234728Y1610684D01*
X2234946Y1607768D01*
X2234728Y1604851D01*
X2233855Y1602809D01*
X2232763Y1601059D01*
X2231453Y1599893D01*
X2229706Y1599018D01*
X2225340D01*
G01X2247643Y1616518D02*
Y1599018D01*
G01X2242621Y1616518D02*
X2252665D01*
G01X2260558Y1599018D02*
Y1616518D01*
G01X2269728D02*
Y1599018D01*
G01Y1607768D02*
X2260558D01*
G01X2281551Y1593185D02*
X2279368Y1596101D01*
X2278276Y1599018D01*
Y1610684D01*
X2279368Y1613601D01*
X2281551Y1616518D01*
G01X2293593Y1599018D02*
Y1610684D01*
G01Y1607476D02*
X2294248Y1608935D01*
X2295340Y1610101D01*
X2296868Y1610684D01*
X2298396Y1610101D01*
X2299488Y1608935D01*
X2300143Y1607476D01*
Y1599018D01*
G01Y1607476D02*
X2300798Y1608935D01*
X2301889Y1610101D01*
X2303418Y1610684D01*
X2304946Y1610101D01*
X2306038Y1608935D01*
X2306693Y1607185D01*
Y1599018D01*
G01X2317643Y1610684D02*
Y1599018D01*
G01Y1615351D02*
X2317206Y1615643D01*
Y1616226D01*
X2317643Y1616518D01*
X2318080Y1616226D01*
Y1615643D01*
X2317643Y1615351D01*
G01X2335143Y1599018D02*
Y1616518D01*
G01X2349368Y1601059D02*
X2350460Y1599893D01*
X2351988Y1599018D01*
X2353298D01*
X2354608Y1599601D01*
X2355481Y1600476D01*
X2355918Y1601642D01*
X2355700Y1603393D01*
X2354826Y1604268D01*
X2350896Y1606018D01*
X2350023Y1608060D01*
X2350460Y1609518D01*
X2351333Y1610393D01*
X2352643Y1610684D01*
X2353953Y1610393D01*
X2355263Y1609518D01*
G01X2371235Y1593185D02*
X2373418Y1596101D01*
X2374510Y1599018D01*
Y1610684D01*
X2373418Y1613601D01*
X2371235Y1616518D01*
G01X2225995Y1571659D02*
X2227523Y1573701D01*
X2228833Y1574868D01*
X2230580Y1575451D01*
X2232108Y1574868D01*
X2233200Y1573701D01*
X2234073Y1571951D01*
X2234291Y1569910D01*
X2234073Y1568159D01*
X2233200Y1566409D01*
X2231889Y1564951D01*
X2230361Y1564368D01*
X2228615Y1564951D01*
X2227086Y1566701D01*
X2226213Y1569326D01*
X2225995Y1572243D01*
X2226431Y1576034D01*
X2227086Y1578077D01*
X2228178Y1580118D01*
X2229706Y1581576D01*
X2231235Y1581868D01*
X2232763Y1581285D01*
X2233855Y1579826D01*
G01X2247643Y1563785D02*
X2247206Y1564076D01*
Y1564660D01*
X2247643Y1564951D01*
X2248080Y1564660D01*
Y1564076D01*
X2247643Y1563785D01*
G01X2260340Y1566992D02*
X2261649Y1565534D01*
X2263178Y1564660D01*
X2265143Y1564368D01*
X2267108Y1564951D01*
X2268636Y1566118D01*
X2269728Y1568159D01*
X2269946Y1570493D01*
X2269510Y1572826D01*
X2268418Y1574285D01*
X2266889Y1575451D01*
X2265361Y1575743D01*
X2263833Y1575451D01*
X2261868Y1574285D01*
X2262523Y1581868D01*
X2268418D01*
G01X2278713Y1563785D02*
X2286573Y1581868D01*
G01X2295340Y1566992D02*
X2296649Y1565534D01*
X2298178Y1564660D01*
X2300143Y1564368D01*
X2302108Y1564951D01*
X2303636Y1566118D01*
X2304728Y1568159D01*
X2304946Y1570493D01*
X2304510Y1572826D01*
X2303418Y1574285D01*
X2301889Y1575451D01*
X2300361Y1575743D01*
X2298833Y1575451D01*
X2296868Y1574285D01*
X2297523Y1581868D01*
X2303418D01*
G01X2317643Y1563785D02*
X2317206Y1564076D01*
Y1564660D01*
X2317643Y1564951D01*
X2318080Y1564660D01*
Y1564076D01*
X2317643Y1563785D01*
G01X2335143Y1581868D02*
X2333396Y1581285D01*
X2332086Y1579826D01*
X2331213Y1578077D01*
X2330558Y1575743D01*
X2330340Y1573118D01*
X2330558Y1570493D01*
X2331213Y1568159D01*
X2332086Y1566409D01*
X2333396Y1564951D01*
X2335143Y1564368D01*
X2336889Y1564951D01*
X2338200Y1566409D01*
X2339073Y1568159D01*
X2339728Y1570493D01*
X2339946Y1573118D01*
X2339728Y1575743D01*
X2339073Y1578077D01*
X2338200Y1579826D01*
X2336889Y1581285D01*
X2335143Y1581868D01*
G01X2225340Y1532342D02*
X2226649Y1530884D01*
X2228178Y1530010D01*
X2230143Y1529718D01*
X2232108Y1530301D01*
X2233636Y1531468D01*
X2234728Y1533509D01*
X2234946Y1535843D01*
X2234510Y1538176D01*
X2233418Y1539635D01*
X2231889Y1540801D01*
X2230361Y1541093D01*
X2228833Y1540801D01*
X2226868Y1539635D01*
X2227523Y1547218D01*
X2233418D01*
G01X2247643Y1529135D02*
X2247206Y1529426D01*
Y1530010D01*
X2247643Y1530301D01*
X2248080Y1530010D01*
Y1529426D01*
X2247643Y1529135D01*
G01X2265143Y1547218D02*
X2263396Y1546635D01*
X2262086Y1545176D01*
X2261213Y1543427D01*
X2260558Y1541093D01*
X2260340Y1538468D01*
X2260558Y1535843D01*
X2261213Y1533509D01*
X2262086Y1531759D01*
X2263396Y1530301D01*
X2265143Y1529718D01*
X2266889Y1530301D01*
X2268200Y1531759D01*
X2269073Y1533509D01*
X2269728Y1535843D01*
X2269946Y1538468D01*
X2269728Y1541093D01*
X2269073Y1543427D01*
X2268200Y1545176D01*
X2266889Y1546635D01*
X2265143Y1547218D01*
G01X2278713Y1529135D02*
X2286573Y1547218D01*
G01X2295995Y1537009D02*
X2297523Y1539051D01*
X2298833Y1540218D01*
X2300580Y1540801D01*
X2302108Y1540218D01*
X2303200Y1539051D01*
X2304073Y1537301D01*
X2304291Y1535260D01*
X2304073Y1533509D01*
X2303200Y1531759D01*
X2301889Y1530301D01*
X2300361Y1529718D01*
X2298615Y1530301D01*
X2297086Y1532051D01*
X2296213Y1534676D01*
X2295995Y1537593D01*
X2296431Y1541384D01*
X2297086Y1543427D01*
X2298178Y1545468D01*
X2299706Y1546926D01*
X2301235Y1547218D01*
X2302763Y1546635D01*
X2303855Y1545176D01*
G01X2317643Y1529135D02*
X2317206Y1529426D01*
Y1530010D01*
X2317643Y1530301D01*
X2318080Y1530010D01*
Y1529426D01*
X2317643Y1529135D01*
G01X2330340Y1532342D02*
X2331649Y1530884D01*
X2333178Y1530010D01*
X2335143Y1529718D01*
X2337108Y1530301D01*
X2338636Y1531468D01*
X2339728Y1533509D01*
X2339946Y1535843D01*
X2339510Y1538176D01*
X2338418Y1539635D01*
X2336889Y1540801D01*
X2335361Y1541093D01*
X2333833Y1540801D01*
X2331868Y1539635D01*
X2332523Y1547218D01*
X2338418D01*
G01X2431393Y1616518D02*
Y1599018D01*
G01X2426371Y1616518D02*
X2436415D01*
G01X2448893Y1599018D02*
Y1606893D01*
X2444526Y1616518D01*
G01X2453260D02*
X2448893Y1606893D01*
G01X2462026Y1599018D02*
Y1616518D01*
X2467266D01*
X2469013Y1615643D01*
X2470323Y1613601D01*
X2470760Y1611268D01*
X2470323Y1608935D01*
X2469231Y1607185D01*
X2467266Y1606309D01*
X2462026D01*
G01X2488260Y1599018D02*
X2479526D01*
Y1616518D01*
X2488260D01*
G01X2484766Y1608060D02*
X2479526D01*
G01X2444090Y1564368D02*
Y1581868D01*
X2448456D01*
X2450203Y1580993D01*
X2451513Y1579826D01*
X2452605Y1578077D01*
X2453478Y1576034D01*
X2453696Y1573118D01*
X2453478Y1570201D01*
X2452605Y1568159D01*
X2451513Y1566409D01*
X2450203Y1565243D01*
X2448456Y1564368D01*
X2444090D01*
G01X2462026D02*
Y1581868D01*
X2467266D01*
X2469013Y1580993D01*
X2470323Y1578951D01*
X2470760Y1576618D01*
X2470323Y1574285D01*
X2469231Y1572535D01*
X2467266Y1571659D01*
X2462026D01*
G01X2444090Y1529718D02*
Y1547218D01*
X2448456D01*
X2450203Y1546343D01*
X2451513Y1545176D01*
X2452605Y1543427D01*
X2453478Y1541384D01*
X2453696Y1538468D01*
X2453478Y1535551D01*
X2452605Y1533509D01*
X2451513Y1531759D01*
X2450203Y1530593D01*
X2448456Y1529718D01*
X2444090D01*
G01X2462026D02*
Y1547218D01*
X2467266D01*
X2469013Y1546343D01*
X2470323Y1544301D01*
X2470760Y1541968D01*
X2470323Y1539635D01*
X2469231Y1537885D01*
X2467266Y1537009D01*
X2462026D01*
G01X2532026Y1599018D02*
Y1616518D01*
X2537485D01*
X2539231Y1615643D01*
X2540323Y1614476D01*
X2540760Y1612143D01*
X2540323Y1609809D01*
X2539013Y1608351D01*
X2537485Y1607476D01*
X2532026D01*
G01X2537485D02*
X2540760Y1599018D01*
G01X2550618Y1606893D02*
X2557605D01*
X2556950Y1608935D01*
X2555858Y1610101D01*
X2554330Y1610684D01*
X2552801Y1610393D01*
X2551491Y1609518D01*
X2550618Y1607476D01*
X2550181Y1605726D01*
Y1603976D01*
X2550618Y1602226D01*
X2551710Y1600476D01*
X2553020Y1599310D01*
X2554548Y1599018D01*
X2556076Y1599601D01*
X2557605Y1601351D01*
G01X2570083Y1599018D02*
Y1613893D01*
X2570520Y1615351D01*
X2571393Y1616226D01*
X2572703Y1616518D01*
X2574013Y1615935D01*
X2574668Y1614476D01*
G01X2572048Y1609518D02*
X2567681D01*
G01X2588893Y1598435D02*
X2588456Y1598726D01*
Y1599310D01*
X2588893Y1599601D01*
X2589330Y1599310D01*
Y1598726D01*
X2588893Y1598435D01*
G01X2619526Y1599018D02*
Y1616518D01*
X2624766D01*
X2626513Y1615643D01*
X2627823Y1613601D01*
X2628260Y1611268D01*
X2627823Y1608935D01*
X2626731Y1607185D01*
X2624766Y1606309D01*
X2619526D01*
G01X2641393Y1599018D02*
Y1616518D01*
G01X2662823Y1599018D02*
Y1610684D01*
G01Y1608643D02*
X2661950Y1609809D01*
X2660639Y1610393D01*
X2659111Y1610684D01*
X2657583Y1610101D01*
X2656273Y1608935D01*
X2655399Y1607185D01*
X2654963Y1604851D01*
X2655399Y1602518D01*
X2656273Y1600768D01*
X2657583Y1599601D01*
X2659111Y1599018D01*
X2660639Y1599310D01*
X2661950Y1600184D01*
X2662823Y1601351D01*
G01X2672681Y1599018D02*
Y1610684D01*
G01Y1607768D02*
X2673555Y1609226D01*
X2674865Y1610393D01*
X2676611Y1610684D01*
X2678139Y1610393D01*
X2679450Y1609226D01*
X2680105Y1607185D01*
Y1599018D01*
G01X2690618Y1606893D02*
X2697605D01*
X2696950Y1608935D01*
X2695858Y1610101D01*
X2694330Y1610684D01*
X2692801Y1610393D01*
X2691491Y1609518D01*
X2690618Y1607476D01*
X2690181Y1605726D01*
Y1603976D01*
X2690618Y1602226D01*
X2691710Y1600476D01*
X2693020Y1599310D01*
X2694548Y1599018D01*
X2696076Y1599601D01*
X2697605Y1601351D01*
G01X2602026Y1581868D02*
Y1564368D01*
X2610760D01*
G01X2619745Y1578951D02*
X2621055Y1580701D01*
X2622583Y1581576D01*
X2624330Y1581868D01*
X2626513Y1581285D01*
X2628041Y1579826D01*
X2628478Y1578077D01*
X2628260Y1576326D01*
X2627386Y1574868D01*
X2623020Y1571951D01*
X2621055Y1569910D01*
X2619745Y1566992D01*
X2619308Y1564368D01*
X2628478D01*
G01X2602026Y1547218D02*
Y1529718D01*
X2610760D01*
G01X2619745Y1544301D02*
X2621055Y1546051D01*
X2622583Y1546926D01*
X2624330Y1547218D01*
X2626513Y1546635D01*
X2628041Y1545176D01*
X2628478Y1543427D01*
X2628260Y1541676D01*
X2627386Y1540218D01*
X2623020Y1537301D01*
X2621055Y1535260D01*
X2619745Y1532342D01*
X2619308Y1529718D01*
X2628478D01*
G01X2811693Y1576034D02*
Y1564368D01*
G01Y1580701D02*
X2811256Y1580993D01*
Y1581576D01*
X2811693Y1581868D01*
X2812130Y1581576D01*
Y1580993D01*
X2811693Y1580701D01*
G01X2825918Y1566409D02*
X2827010Y1565243D01*
X2828538Y1564368D01*
X2829848D01*
X2831158Y1564951D01*
X2832031Y1565826D01*
X2832468Y1566992D01*
X2832250Y1568743D01*
X2831376Y1569618D01*
X2827446Y1571368D01*
X2826573Y1573410D01*
X2827010Y1574868D01*
X2827883Y1575743D01*
X2829193Y1576034D01*
X2830503Y1575743D01*
X2831813Y1574868D01*
G01X2859171Y1564368D02*
Y1581868D01*
X2869215Y1564368D01*
Y1581868D01*
G01X2881693Y1564368D02*
X2879946Y1564660D01*
X2878418Y1565826D01*
X2877108Y1567576D01*
X2876234Y1569618D01*
X2875798Y1571951D01*
Y1574285D01*
X2876234Y1576618D01*
X2877108Y1578660D01*
X2878418Y1580409D01*
X2879946Y1581576D01*
X2881693Y1581868D01*
X2883439Y1581576D01*
X2884968Y1580409D01*
X2886278Y1578660D01*
X2887152Y1576618D01*
X2887588Y1574285D01*
Y1571951D01*
X2887152Y1569618D01*
X2886278Y1567576D01*
X2884968Y1565826D01*
X2883439Y1564660D01*
X2881693Y1564368D01*
G01X2899193Y1581868D02*
Y1564368D01*
G01X2894171Y1581868D02*
X2904215D01*
G01X2930481Y1576034D02*
Y1567868D01*
X2931355Y1565826D01*
X2932665Y1564660D01*
X2934193Y1564368D01*
X2935721Y1564660D01*
X2937031Y1565826D01*
X2937905Y1567868D01*
G01Y1564368D02*
Y1576034D01*
G01X2948418Y1566409D02*
X2949510Y1565243D01*
X2951038Y1564368D01*
X2952348D01*
X2953658Y1564951D01*
X2954531Y1565826D01*
X2954968Y1566992D01*
X2954750Y1568743D01*
X2953876Y1569618D01*
X2949946Y1571368D01*
X2949073Y1573410D01*
X2949510Y1574868D01*
X2950383Y1575743D01*
X2951693Y1576034D01*
X2953003Y1575743D01*
X2954313Y1574868D01*
G01X2965918Y1572243D02*
X2972905D01*
X2972250Y1574285D01*
X2971158Y1575451D01*
X2969630Y1576034D01*
X2968101Y1575743D01*
X2966791Y1574868D01*
X2965918Y1572826D01*
X2965481Y1571076D01*
Y1569326D01*
X2965918Y1567576D01*
X2967010Y1565826D01*
X2968320Y1564660D01*
X2969848Y1564368D01*
X2971376Y1564951D01*
X2972905Y1566701D01*
G01X2990623Y1581868D02*
Y1564368D01*
G01Y1566992D02*
X2989750Y1565534D01*
X2988439Y1564660D01*
X2986911Y1564368D01*
X2985165Y1564951D01*
X2983855Y1566409D01*
X2982981Y1568159D01*
X2982763Y1570201D01*
X2982981Y1572243D01*
X2983855Y1573993D01*
X2985165Y1575451D01*
X2986911Y1576034D01*
X2988439Y1575743D01*
X2989531Y1575159D01*
X2990623Y1573993D01*
G01X2736890Y1598435D02*
X2746496Y1611268D01*
G01X2741693Y1613601D02*
Y1596101D01*
G01X2746496Y1598435D02*
X2736890Y1611268D01*
G01X2735143Y1604851D02*
X2748243D01*
G01X2773855D02*
X2779531D01*
G01X2806890Y1599018D02*
Y1616518D01*
X2811256D01*
X2813003Y1615643D01*
X2814313Y1614476D01*
X2815405Y1612727D01*
X2816278Y1610684D01*
X2816496Y1607768D01*
X2816278Y1604851D01*
X2815405Y1602809D01*
X2814313Y1601059D01*
X2813003Y1599893D01*
X2811256Y1599018D01*
X2806890D01*
G01X2825918Y1606893D02*
X2832905D01*
X2832250Y1608935D01*
X2831158Y1610101D01*
X2829630Y1610684D01*
X2828101Y1610393D01*
X2826791Y1609518D01*
X2825918Y1607476D01*
X2825481Y1605726D01*
Y1603976D01*
X2825918Y1602226D01*
X2827010Y1600476D01*
X2828320Y1599310D01*
X2829848Y1599018D01*
X2831376Y1599601D01*
X2832905Y1601351D01*
G01X2842981Y1599018D02*
Y1610684D01*
G01Y1607768D02*
X2843855Y1609226D01*
X2845165Y1610393D01*
X2846911Y1610684D01*
X2848439Y1610393D01*
X2849750Y1609226D01*
X2850405Y1607185D01*
Y1599018D01*
G01X2864193D02*
X2862883Y1599310D01*
X2861573Y1600476D01*
X2860699Y1602518D01*
X2860263Y1604851D01*
X2860699Y1607185D01*
X2861573Y1609226D01*
X2862883Y1610393D01*
X2864193Y1610684D01*
X2865503Y1610393D01*
X2866813Y1609226D01*
X2867686Y1607185D01*
X2867905Y1604851D01*
X2867686Y1602518D01*
X2866813Y1600476D01*
X2865503Y1599310D01*
X2864193Y1599018D01*
G01X2881693Y1616518D02*
Y1599018D01*
G01X2878636Y1610684D02*
X2884750D01*
G01X2895918Y1606893D02*
X2902905D01*
X2902250Y1608935D01*
X2901158Y1610101D01*
X2899630Y1610684D01*
X2898101Y1610393D01*
X2896791Y1609518D01*
X2895918Y1607476D01*
X2895481Y1605726D01*
Y1603976D01*
X2895918Y1602226D01*
X2897010Y1600476D01*
X2898320Y1599310D01*
X2899848Y1599018D01*
X2901376Y1599601D01*
X2902905Y1601351D01*
G01X2913418Y1601059D02*
X2914510Y1599893D01*
X2916038Y1599018D01*
X2917348D01*
X2918658Y1599601D01*
X2919531Y1600476D01*
X2919968Y1601642D01*
X2919750Y1603393D01*
X2918876Y1604268D01*
X2914946Y1606018D01*
X2914073Y1608060D01*
X2914510Y1609518D01*
X2915383Y1610393D01*
X2916693Y1610684D01*
X2918003Y1610393D01*
X2919313Y1609518D01*
G01X2951693Y1616518D02*
Y1599018D01*
G01X2948636Y1610684D02*
X2954750D01*
G01X2965481Y1599018D02*
Y1616518D01*
G01Y1608060D02*
X2966573Y1609518D01*
X2967665Y1610393D01*
X2969411Y1610684D01*
X2970721Y1610393D01*
X2972250Y1609226D01*
X2972905Y1607476D01*
Y1599018D01*
G01X2990623D02*
Y1610684D01*
G01Y1608643D02*
X2989750Y1609809D01*
X2988439Y1610393D01*
X2986911Y1610684D01*
X2985383Y1610101D01*
X2984073Y1608935D01*
X2983199Y1607185D01*
X2982763Y1604851D01*
X2983199Y1602518D01*
X2984073Y1600768D01*
X2985383Y1599601D01*
X2986911Y1599018D01*
X2988439Y1599310D01*
X2989750Y1600184D01*
X2990623Y1601351D01*
G01X3004193Y1616518D02*
Y1599018D01*
G01X3001136Y1610684D02*
X3007250D01*
G01X3039193Y1616518D02*
Y1599018D01*
G01X3036136Y1610684D02*
X3042250D01*
G01X3052981Y1599018D02*
Y1616518D01*
G01Y1608060D02*
X3054073Y1609518D01*
X3055165Y1610393D01*
X3056911Y1610684D01*
X3058221Y1610393D01*
X3059750Y1609226D01*
X3060405Y1607476D01*
Y1599018D01*
G01X3074193Y1610684D02*
Y1599018D01*
G01Y1615351D02*
X3073756Y1615643D01*
Y1616226D01*
X3074193Y1616518D01*
X3074630Y1616226D01*
Y1615643D01*
X3074193Y1615351D01*
G01X3088418Y1601059D02*
X3089510Y1599893D01*
X3091038Y1599018D01*
X3092348D01*
X3093658Y1599601D01*
X3094531Y1600476D01*
X3094968Y1601642D01*
X3094750Y1603393D01*
X3093876Y1604268D01*
X3089946Y1606018D01*
X3089073Y1608060D01*
X3089510Y1609518D01*
X3090383Y1610393D01*
X3091693Y1610684D01*
X3093003Y1610393D01*
X3094313Y1609518D01*
G01X3124073Y1616518D02*
X3129313D01*
G01X3126693D02*
Y1599018D01*
G01X3124073D02*
X3129313D01*
G01X3137643D02*
Y1610684D01*
G01Y1607476D02*
X3138298Y1608935D01*
X3139390Y1610101D01*
X3140918Y1610684D01*
X3142446Y1610101D01*
X3143538Y1608935D01*
X3144193Y1607476D01*
Y1599018D01*
G01Y1607476D02*
X3144848Y1608935D01*
X3145939Y1610101D01*
X3147468Y1610684D01*
X3148996Y1610101D01*
X3150088Y1608935D01*
X3150743Y1607185D01*
Y1599018D01*
G01X3157763Y1593185D02*
Y1610684D01*
G01Y1608060D02*
X3158855Y1609518D01*
X3159946Y1610393D01*
X3161693Y1610684D01*
X3163221Y1610393D01*
X3164750Y1608935D01*
X3165405Y1606893D01*
X3165623Y1604851D01*
X3165405Y1602809D01*
X3164750Y1600768D01*
X3163439Y1599601D01*
X3161693Y1599018D01*
X3160165Y1599310D01*
X3158636Y1600184D01*
X3157763Y1601351D01*
G01X3175918Y1606893D02*
X3182905D01*
X3182250Y1608935D01*
X3181158Y1610101D01*
X3179630Y1610684D01*
X3178101Y1610393D01*
X3176791Y1609518D01*
X3175918Y1607476D01*
X3175481Y1605726D01*
Y1603976D01*
X3175918Y1602226D01*
X3177010Y1600476D01*
X3178320Y1599310D01*
X3179848Y1599018D01*
X3181376Y1599601D01*
X3182905Y1601351D01*
G01X3200623Y1616518D02*
Y1599018D01*
G01Y1601642D02*
X3199750Y1600184D01*
X3198439Y1599310D01*
X3196911Y1599018D01*
X3195165Y1599601D01*
X3193855Y1601059D01*
X3192981Y1602809D01*
X3192763Y1604851D01*
X3192981Y1606893D01*
X3193855Y1608643D01*
X3195165Y1610101D01*
X3196911Y1610684D01*
X3198439Y1610393D01*
X3199531Y1609809D01*
X3200623Y1608643D01*
G01X3218123Y1599018D02*
Y1610684D01*
G01Y1608643D02*
X3217250Y1609809D01*
X3215939Y1610393D01*
X3214411Y1610684D01*
X3212883Y1610101D01*
X3211573Y1608935D01*
X3210699Y1607185D01*
X3210263Y1604851D01*
X3210699Y1602518D01*
X3211573Y1600768D01*
X3212883Y1599601D01*
X3214411Y1599018D01*
X3215939Y1599310D01*
X3217250Y1600184D01*
X3218123Y1601351D01*
G01X3227981Y1599018D02*
Y1610684D01*
G01Y1607768D02*
X3228855Y1609226D01*
X3230165Y1610393D01*
X3231911Y1610684D01*
X3233439Y1610393D01*
X3234750Y1609226D01*
X3235405Y1607185D01*
Y1599018D01*
G01X3252686Y1609226D02*
X3251158Y1610393D01*
X3249848Y1610684D01*
X3248101Y1610101D01*
X3246791Y1608935D01*
X3245918Y1606893D01*
X3245699Y1604851D01*
X3245918Y1602809D01*
X3246791Y1601059D01*
X3248101Y1599601D01*
X3249848Y1599018D01*
X3251376Y1599601D01*
X3252686Y1600768D01*
G01X3263418Y1606893D02*
X3270405D01*
X3269750Y1608935D01*
X3268658Y1610101D01*
X3267130Y1610684D01*
X3265601Y1610393D01*
X3264291Y1609518D01*
X3263418Y1607476D01*
X3262981Y1605726D01*
Y1603976D01*
X3263418Y1602226D01*
X3264510Y1600476D01*
X3265820Y1599310D01*
X3267348Y1599018D01*
X3268876Y1599601D01*
X3270405Y1601351D01*
G01X0Y-137756D02*
G03X15000Y-152756I15000J0D01*
G01X0Y-137756D02*
G03X15000Y-152756I15000J0D01*
G01X0Y-11811D02*
Y-137756D01*
G01Y-11811D02*
Y-137756D01*
G01X854331Y-152756D02*
X15000D01*
G01X854331D02*
X15000D01*
G01X23622Y-7874D02*
G03Y0I0J3937D01*
G01Y-7874D02*
G03Y0I0J3937D01*
G01X0Y3937D02*
G03X3937Y0I3937J0D01*
G01Y-7874D02*
X23622D01*
G01X0Y3937D02*
G03X3937Y0I3937J0D01*
G01Y-7874D02*
X23622D01*
G01X3937D02*
G03X0Y-11811I0J-3937D01*
G01X3937Y-7874D02*
G03X0Y-11811I0J-3937D01*
G01X3937Y0D02*
X397638D01*
G01X3937D02*
X397638D01*
G01X0Y1370866D02*
Y3937D01*
G01Y1370866D02*
Y3937D01*
G01X3937Y1374803D02*
G03X0Y1370866I0J-3937D01*
G01X3937Y1374803D02*
G03X0Y1370866I0J-3937D01*
G01X23622Y1374803D02*
G03Y1382677I0J3937D01*
G01Y1374803D02*
G03Y1382677I0J3937D01*
G01X3937D02*
X23622D01*
G01X0Y1386614D02*
G03X3937Y1382677I3937J0D01*
G01D02*
X23622D01*
G01X0Y1386614D02*
G03X3937Y1382677I3937J0D01*
G01Y1374803D02*
X746850D01*
G01D02*
X3937D01*
G01X0Y1386614D02*
Y1643268D01*
G01Y1386614D02*
Y1643268D01*
G01X15000Y1658268D02*
G03X0Y1643268I0J-15000D01*
G01X15000Y1658268D02*
G03X0Y1643268I0J-15000D01*
G01X775591Y1658268D02*
X15000D01*
G01X775591D02*
X15000D01*
G01X54331Y-7874D02*
X323228D01*
G01X54331D02*
X323228D01*
G01X54331Y0D02*
G03Y-7874I0J-3937D01*
G01Y0D02*
G03Y-7874I0J-3937D01*
G01Y1382677D02*
G03Y1374803I0J-3937D01*
G01Y1382677D02*
G03Y1374803I0J-3937D01*
G01Y1382677D02*
X353740D01*
G01X54331D02*
X353740D01*
G01X114295Y378885D02*
G03X148106I16905J-13531D01*
G01X114295D02*
G03X148106I16905J-13531D01*
G01X114295D02*
G03X121220Y392016I-30737J24602D01*
G01X114295Y378885D02*
G03X121220Y392016I-30737J24602D01*
G01X114295Y831641D02*
G03X121220Y844772I-30737J24601D01*
G01X114295Y831641D02*
G03X121220Y844772I-30737J24602D01*
G01X114295Y831641D02*
G03X148106I16905J-13531D01*
G01X114295D02*
G03X148106I16905J-13531D01*
G01X114295Y1284397D02*
G03X148106I16905J-13531D01*
G01X114295D02*
G03X148106I16905J-13531D01*
G01X114295D02*
G03X121220Y1297528I-30737J24601D01*
G01X114295Y1284397D02*
G03X121220Y1297528I-30737J24602D01*
G01X141181Y392016D02*
G03X121220I-9980J-3039D01*
G01X141181D02*
G03X148106Y378885I37662J11471D01*
G01X141181Y392016D02*
G03X121220I-9980J-3039D01*
G01X141181D02*
G03X148106Y378885I37662J11471D01*
G01X141181Y844772D02*
G03X148106Y831641I37662J11471D01*
G01X141181Y844772D02*
G03X148106Y831641I37662J11471D01*
G01X141181Y844772D02*
G03X121220I-9980J-3040D01*
G01X141181D02*
G03X121220I-9980J-3039D01*
G01X141181Y1297528D02*
G03X121220I-9980J-3040D01*
G01X141181D02*
G03X148106Y1284397I37662J11471D01*
G01X141181Y1297528D02*
G03X121220I-9980J-3040D01*
G01X141181D02*
G03X148106Y1284397I37662J11471D01*
G01X323228Y-7874D02*
G03Y0I0J3937D01*
G01Y-7874D02*
G03Y0I0J3937D01*
G01X362598D02*
G03Y-7874I0J-3937D01*
G01Y0D02*
G03Y-7874I0J-3937D01*
G01X362327Y378885D02*
G03X396138I16905J-13531D01*
G01X362327D02*
G03X396138I16905J-13531D01*
G01X362327D02*
G03X369252Y392016I-30737J24602D01*
G01X362327Y378885D02*
G03X369252Y392016I-30737J24602D01*
G01X362327Y831641D02*
G03X369252Y844772I-30737J24602D01*
G01X362327Y831641D02*
G03X369252Y844772I-30737J24602D01*
G01X362327Y831641D02*
G03X396138I16905J-13531D01*
G01X362327D02*
G03X396138I16905J-13531D01*
G01X362327Y1284397D02*
G03X396138I16905J-13531D01*
G01X362327D02*
G03X396138I16905J-13531D01*
G01X362327D02*
G03X369252Y1297528I-30737J24602D01*
G01X362327Y1284397D02*
G03X369252Y1297528I-30737J24602D01*
G01X353740Y1374803D02*
G03Y1382677I0J3937D01*
G01Y1374803D02*
G03Y1382677I0J3937D01*
G01X401575Y3937D02*
Y55118D01*
G01X397638Y0D02*
G03X401575Y3937I0J3937D01*
G01X409449D02*
Y51181D01*
G01X397638Y-7874D02*
G03X409449Y3937I0J11811D01*
G01X397638Y0D02*
G03X401575Y3937I0J3937D01*
G01D02*
Y55118D01*
G01X409449Y3937D02*
Y51181D01*
G01X397638Y-7874D02*
G03X409449Y3937I0J11811D01*
G01X362598Y-7874D02*
X397638D01*
G01X362598D02*
X397638D01*
G01X405512Y59055D02*
G03X401575Y55118I0J-3937D01*
G01X405512Y59055D02*
G03X401575Y55118I0J-3937D01*
G01X405512Y59055D02*
X586614D01*
G01X409449Y51181D02*
X582677D01*
G01X405512Y59055D02*
X586614D01*
G01X409449Y51181D02*
X582677D01*
G01X389213Y392016D02*
G03X396138Y378885I37662J11471D01*
G01X389213Y392016D02*
G03X396138Y378885I37662J11471D01*
G01X389213Y392016D02*
G03X369252I-9981J-3039D01*
G01X389213D02*
G03X369252I-9981J-3039D01*
G01X389213Y844772D02*
G03X396138Y831641I37662J11471D01*
G01X389213Y844772D02*
G03X396138Y831641I37662J11471D01*
G01X389213Y844772D02*
G03X369252I-9981J-3040D01*
G01X389213D02*
G03X369252I-9981J-3039D01*
G01X389213Y1297528D02*
G03X396138Y1284397I37662J11471D01*
G01X389213Y1297528D02*
G03X396138Y1284397I37662J11471D01*
G01X389213Y1297528D02*
G03X369252I-9981J-3040D01*
G01X389213D02*
G03X369252I-9981J-3040D01*
G01X393110Y1382677D02*
G03Y1374803I0J-3937D01*
G01Y1382677D02*
X692520D01*
G01X393110D02*
X692520D01*
G01X393110D02*
G03Y1374803I0J-3937D01*
G01X523327Y829921D02*
G03X483169I-20079J0D01*
G01X523327D02*
G03I-20079J0D01*
G01X483169D02*
G03X523327I20079J0D01*
G01X594488Y-7874D02*
X628765D01*
G01X594488D02*
X628765D01*
G01X590551Y55118D02*
Y3937D01*
G01D02*
G03X594488Y0I3937J0D01*
G01X582677Y51181D02*
Y3937D01*
G01D02*
G03X594488Y-7874I11811J0D01*
G01X590551Y55118D02*
Y3937D01*
G01D02*
G03X594488Y0I3937J0D01*
G01X582677Y51181D02*
Y3937D01*
G01D02*
G03X594488Y-7874I11811J0D01*
G01Y0D02*
X783465D01*
G01X594488D02*
X783465D01*
G01X590551Y55118D02*
G03X586614Y59055I-3937J0D01*
G01X590551Y55118D02*
G03X586614Y59055I-3937J0D01*
G01X628765Y-7874D02*
G03Y0I0J3937D01*
G01Y-7874D02*
G03Y0I0J3937D01*
G01X610358Y378885D02*
G03X644169I16906J-13531D01*
G01X610358D02*
G03X644169I16906J-13531D01*
G01X637244Y392016D02*
G03X644169Y378885I37662J11471D01*
G01X637244Y392016D02*
G03X644169Y378885I37662J11471D01*
G01X637244Y392016D02*
G03X617283I-9980J-3039D01*
G01X637244D02*
G03X617283I-9980J-3039D01*
G01X610358Y378885D02*
G03X617283Y392016I-30737J24602D01*
G01X610358Y378885D02*
G03X617283Y392016I-30737J24602D01*
G01X637244Y844772D02*
G03X644169Y831641I37662J11471D01*
G01X637244Y844772D02*
G03X644169Y831641I37662J11471D01*
G01X610358D02*
G03X617283Y844772I-30737J24601D01*
G01X610358Y831641D02*
G03X617283Y844772I-30737J24602D01*
G01X610358Y831641D02*
G03X644169I16906J-13531D01*
G01X610358D02*
G03X644169I16906J-13531D01*
G01X637244Y844772D02*
G03X617283I-9980J-3040D01*
G01X637244D02*
G03X617283I-9980J-3039D01*
G01X610358Y1284397D02*
G03X644169I16906J-13531D01*
G01X610358D02*
G03X644169I16906J-13531D01*
G01X637244Y1297528D02*
G03X644169Y1284397I37662J11471D01*
G01X637244Y1297528D02*
G03X644169Y1284397I37662J11471D01*
G01X610358D02*
G03X617283Y1297528I-30737J24601D01*
G01X637244D02*
G03X617283I-9980J-3040D01*
G01X610358Y1284397D02*
G03X617283Y1297528I-30737J24602D01*
G01X637244D02*
G03X617283I-9980J-3040D01*
G01X659474Y0D02*
G03Y-7874I0J-3937D01*
G01Y0D02*
G03Y-7874I0J-3937D01*
G01D02*
X780203D01*
G01X659474D02*
X780203D01*
G01X692520Y1374803D02*
G03Y1382677I0J3937D01*
G01Y1374803D02*
G03Y1382677I0J3937D01*
G01X746850Y1374803D02*
G03X750787Y1378740I0J3937D01*
G01X746850Y1374803D02*
G03X750787Y1378740I0J3937D01*
G01X723228Y1382677D02*
G03Y1374803I0J-3937D01*
G01Y1382677D02*
X742913D01*
G01X723228D02*
X742913D01*
G01X723228D02*
G03Y1374803I0J-3937D01*
G01X742913Y1464567D02*
Y1382677D01*
G01Y1464567D02*
Y1382677D01*
G01X754724Y1476378D02*
G03X742913Y1464567I0J-11811D01*
G01X754724Y1476378D02*
G03X742913Y1464567I0J-11811D01*
G01X862205Y-7874D02*
X791339D01*
G01X787402Y-3937D02*
G03X791339Y-7874I3937J0D01*
G01X787402Y-3937D02*
G03X791339Y-7874I3937J0D01*
G01D02*
X862205D01*
G01X858268Y-15748D02*
X791339D01*
G01X858268D02*
X791339D01*
G01X787402Y-3937D02*
G03X783465Y0I-3937J0D01*
G01X787402Y-3937D02*
G03X783465Y0I-3937J0D01*
G01X780203Y-7874D02*
G03X791339Y-15748I11136J3937D01*
G01X780203Y-7874D02*
G03X791339Y-15748I11136J3937D01*
G01X779551Y264712D02*
G03X813362I16905J-13531D01*
G01X779551D02*
G03X813362I16905J-13531D01*
G01X779551D02*
G03X786476Y277843I-30737J24601D01*
G01X806437D02*
G03X786476I-9981J-3040D01*
G01X779551Y264712D02*
G03X786476Y277843I-30737J24602D01*
G01X806437D02*
G03X786476I-9981J-3040D01*
G01X779551Y737153D02*
G03X786476Y750284I-30737J24601D01*
G01X779551Y737154D02*
G03X786476Y750284I-30736J24602D01*
G01X779551Y737153D02*
G03X813362I16905J-13531D01*
G01X779551D02*
G03X813362I16905J-13531D01*
G01X806437Y750284D02*
G03X786476I-9981J-3040D01*
G01X806437D02*
G03X786476I-9981J-3040D01*
G01X750787Y1464567D02*
Y1378740D01*
G01Y1464567D02*
Y1378740D01*
G01X783465Y1468504D02*
G03X787402Y1472441I0J3937D01*
G01X783465Y1468504D02*
G03X787402Y1472441I0J3937D01*
G01X783465Y1468504D02*
X754724D01*
G01D02*
G03X750787Y1464567I0J-3937D01*
G01X783465Y1468504D02*
X754724D01*
G01D02*
G03X750787Y1464567I0J-3937D01*
G01X779528Y1476378D02*
X754724D01*
G01X779528D02*
X754724D01*
G01X787402Y1654331D02*
Y1472441D01*
G01X779528Y1596063D02*
Y1476378D01*
G01X787402Y1654331D02*
Y1472441D01*
G01X779528Y1596063D02*
Y1476378D01*
G01X787402Y1596063D02*
G03X779528I-3937J0D01*
G01X787402D02*
G03X779528I-3937J0D01*
G01X1216535Y1658268D02*
X791339D01*
G01D02*
G03X787402Y1654331I0J-3937D01*
G01X779528D02*
G03X775591Y1658268I-3937J0D01*
G01X1216535D02*
X791339D01*
G01D02*
G03X787402Y1654331I0J-3937D01*
G01X779528D02*
G03X775591Y1658268I-3937J0D01*
G01X779528Y1654331D02*
Y1626772D01*
G01D02*
G03X787402I3937J0D01*
G01X779528Y1654331D02*
Y1626772D01*
G01D02*
G03X787402I3937J0D01*
G01X806437Y277843D02*
G03X813362Y264712I37662J11471D01*
G01X806437Y277843D02*
G03X813362Y264712I37662J11471D01*
G01X806437Y750284D02*
G03X813362Y737153I37662J11471D01*
G01X806437Y750284D02*
G03X813362Y737154I37661J11472D01*
G01X866142Y-148819D02*
Y-11811D01*
G01Y-148819D02*
G03X870079Y-152756I3937J0D01*
G01X866142Y-11811D02*
Y-148819D01*
G01D02*
G03X870079Y-152756I3937J0D01*
G01X866142Y-129134D02*
G03X858268I-3937J0D01*
G01X866142D02*
G03X858268I-3937J0D01*
G01Y-148819D02*
Y-129134D01*
G01X854331Y-152756D02*
G03X858268Y-148819I0J3937D01*
G01D02*
Y-129134D01*
G01X854331Y-152756D02*
G03X858268Y-148819I0J3937D01*
G01X1177165Y-152756D02*
X870079D01*
G01D02*
X1177165D01*
G01X858268Y-98425D02*
Y-15748D01*
G01Y-98425D02*
Y-15748D01*
G01Y-98425D02*
G03X866142I3937J0D01*
G01X858268D02*
G03X866142I3937J0D01*
G01Y-11811D02*
G03X862205Y-7874I-3937J0D01*
G01X866142Y-11811D02*
G03X862205Y-7874I-3937J0D01*
G01X927032Y-57820D02*
G03X962731I17850J-12259D01*
G01X927032Y-57821D02*
G03X962732I17850J-12258D01*
G01X927032Y-57820D02*
G03X935199Y-42571I-64908J44575D01*
G01X954565D02*
G03X935199I-9683J-3885D01*
G01X927032Y-57821D02*
G03X935199Y-42571I-64909J44573D01*
G01X954564D02*
G03X935199I-9682J-3885D01*
G01X944512Y1089122D02*
G03X978323I16905J-13531D01*
G01X944512Y1089121D02*
G03X978323I16905J-13531D01*
G01X944512Y1431641D02*
G03X978323I16905J-13531D01*
G01X944512D02*
G03X978323I16905J-13531D01*
G01X954565Y-42571D02*
G03X962731Y-57820I73077J29322D01*
G01X954564Y-42570D02*
G03X962732Y-57821I73076J29324D01*
G01X971398Y1102252D02*
G03X978323Y1089122I37661J11472D01*
G01X971398Y1102252D02*
G03X978323Y1089121I37662J11471D01*
G01X971398Y1102252D02*
G03X951437I-9980J-3039D01*
G01X971398D02*
G03X951437I-9980J-3039D01*
G01X944512Y1089122D02*
G03X951437Y1102252I-30737J24602D01*
G01X944512Y1089121D02*
G03X951437Y1102252I-30737J24602D01*
G01X971398Y1444772D02*
G03X978323Y1431641I37662J11471D01*
G01X971398Y1444772D02*
G03X978323Y1431641I37662J11471D01*
G01X971398Y1444772D02*
G03X951437I-9980J-3040D01*
G01X944512Y1431641D02*
G03X951437Y1444772I-30737J24602D01*
G01X944512Y1431641D02*
G03X951437Y1444772I-30737J24602D01*
G01X971398D02*
G03X951437I-9980J-3039D01*
G01X1181102Y-148819D02*
Y-3937D01*
G01X1177165Y-152756D02*
G03X1181102Y-148819I0J3937D01*
G01X1177165Y-152756D02*
G03X1181102Y-148819I0J3937D01*
G01D02*
Y-3937D01*
G01Y-94488D02*
G03X1188976I3937J0D01*
G01X1181102D02*
G03X1188976I3937J0D01*
G01Y-125197D02*
G03X1181102I-3937J0D01*
G01X1188976D02*
G03X1181102I-3937J0D01*
G01X1185039Y0D02*
G03X1181102Y-3937I0J-3937D01*
G01X1185039Y0D02*
G03X1181102Y-3937I0J-3937D01*
G01X1164984Y557626D02*
G03X1198795I16906J-13531D01*
G01X1164984Y557625D02*
G03X1198795I16906J-13531D01*
G01X1191870Y570756D02*
G03X1171909I-9980J-3039D01*
G01X1191870D02*
G03X1171909I-9980J-3039D01*
G01X1164984Y557626D02*
G03X1171909Y570756I-30736J24602D01*
G01X1164984Y557625D02*
G03X1171909Y570756I-30737J24602D01*
G01X1164984Y971011D02*
G03X1198795I16906J-13531D01*
G01X1164984D02*
G03X1198795I16906J-13531D01*
G01X1191870Y984142D02*
G03X1171909I-9980J-3040D01*
G01X1191870D02*
G03X1171909I-9980J-3039D01*
G01X1164984Y971011D02*
G03X1171909Y984142I-30737J24602D01*
G01X1164984Y971011D02*
G03X1171909Y984142I-30737J24602D01*
G01X1164173Y1378740D02*
Y1468504D01*
G01X1930906Y1374803D02*
X1168110D01*
G01X1164173Y1378740D02*
G03X1168110Y1374803I3937J0D01*
G01X1172047Y1382677D02*
Y1464567D01*
G01X1195669Y1382677D02*
X1172047D01*
G01X1930906Y1374803D02*
X1168110D01*
G01X1164173Y1378740D02*
G03X1168110Y1374804I3937J1D01*
G01X1164173Y1378740D02*
Y1468504D01*
G01X1172047Y1382677D02*
Y1464567D01*
G01X1195669Y1382677D02*
X1172047D01*
G01X1168110Y1472441D02*
G03X1164173Y1468504I0J-3937D01*
G01X1168110Y1472441D02*
G03X1164173Y1468504I0J-3937D01*
G01X1172047Y1464567D02*
X1216535D01*
G01X1172047D02*
X1216535D01*
G01X1168110Y1472441D02*
X1216535D01*
G01X1168110D02*
X1216535D01*
G01X1164984Y1561563D02*
G03X1171909Y1574693I-30736J24602D01*
G01X1164984Y1561562D02*
G03X1171909Y1574693I-30737J24602D01*
G01X1164984Y1561563D02*
G03X1198795I16906J-13531D01*
G01X1164984Y1561562D02*
G03X1198795I16906J-13531D01*
G01X1191870Y1574693D02*
G03X1171909I-9980J-3039D01*
G01X1191870D02*
G03X1171909I-9980J-3039D01*
G01X1188976Y-148819D02*
Y-125197D01*
G01Y-148819D02*
G03X1192913Y-152756I3937J0D01*
G01X1188976Y-148819D02*
Y-125197D01*
G01Y-148819D02*
G03X1192913Y-152756I3937J0D01*
G01D02*
X1919843D01*
G01X1192913D02*
X1919843D01*
G01X1188976Y-94488D02*
Y-7874D01*
G01Y-94488D02*
Y-7874D01*
G01X1185039Y0D02*
X1366142D01*
G01X1188976Y-7874D02*
X1315748D01*
G01X1185039Y0D02*
X1366142D01*
G01X1188976Y-7874D02*
X1315748D01*
G01X1191870Y570756D02*
G03X1198795Y557626I37662J11472D01*
G01X1191870Y570756D02*
G03X1198795Y557626I37662J11472D01*
G01X1191870Y984142D02*
G03X1198795Y971011I37662J11471D01*
G01X1191870Y984142D02*
G03X1198795Y971011I37662J11471D01*
G01X1524606Y1382677D02*
X1226378D01*
G01X1524606D02*
X1226378D01*
G01X1195669Y1374803D02*
G03Y1382677I0J3937D01*
G01X1226378D02*
G03Y1374803I0J-3937D01*
G01X1195669D02*
G03Y1382677I0J3937D01*
G01X1226378D02*
G03Y1374803I0J-3937D01*
G01X1216535Y1464567D02*
G03X1228346Y1476378I0J11811D01*
G01X1216535Y1464567D02*
G03X1228346Y1476378I0J11811D01*
G01Y1592126D02*
Y1476378D01*
G01Y1592126D02*
Y1476378D01*
G01X1220472Y1654331D02*
Y1476378D01*
G01X1216535Y1472441D02*
G03X1220472Y1476378I0J3937D01*
G01X1216535Y1472441D02*
G03X1220472Y1476378I0J3937D01*
G01D02*
Y1654331D01*
G01X1191870Y1574693D02*
G03X1198795Y1561563I37662J11472D01*
G01X1191870Y1574693D02*
G03X1198795Y1561562I37662J11471D01*
G01X1228346Y1592126D02*
G03X1220472I-3937J0D01*
G01X1228346D02*
G03X1220472I-3937J0D01*
G01X1232283Y1658268D02*
X1442382D01*
G01X1232283D02*
G03X1228346Y1654331I0J-3937D01*
G01X1232283Y1658268D02*
X1442382D01*
G01X1232283D02*
G03X1228346Y1654331I0J-3937D01*
G01D02*
Y1622835D01*
G01Y1654331D02*
Y1622835D01*
G01X1220472Y1654331D02*
G03X1216535Y1658268I-3937J0D01*
G01X1220472Y1654331D02*
G03X1216535Y1658268I-3937J0D01*
G01X1220472Y1622835D02*
G03X1228346I3937J0D01*
G01X1220472D02*
G03X1228346I3937J0D01*
G01X1284965Y378885D02*
G03X1318776I16906J-13531D01*
G01X1284965D02*
G03X1318775I16905J-13531D01*
G01X1284965Y831641D02*
G03X1318776I16906J-13531D01*
G01X1284965D02*
G03X1318775I16905J-13531D01*
G01X1284965Y1284397D02*
G03X1318776I16906J-13531D01*
G01X1284965D02*
G03X1318775I16905J-13531D01*
G01X1315748Y-7874D02*
G03Y0I0J3937D01*
G01Y-7874D02*
G03Y0I0J3937D01*
G01X1311850Y392016D02*
G03X1291890I-9980J-3040D01*
G01X1311850D02*
G03X1318776Y378885I37662J11473D01*
G01X1311851Y392016D02*
G03X1291890I-9980J-3039D01*
G01X1311851D02*
G03X1318775Y378885I37663J11469D01*
G01X1284965D02*
G03X1291890Y392016I-30737J24602D01*
G01X1284965Y378885D02*
G03X1291890Y392016I-30737J24602D01*
G01X1284965Y831641D02*
G03X1291890Y844772I-30737J24602D01*
G01X1311850D02*
G03X1318776Y831641I37662J11473D01*
G01X1284965D02*
G03X1291890Y844772I-30737J24602D01*
G01X1311851D02*
G03X1318775Y831641I37663J11469D01*
G01X1311850Y844772D02*
G03X1291890I-9980J-3040D01*
G01X1311851D02*
G03X1291890I-9980J-3039D01*
G01X1284965Y1284397D02*
G03X1291890Y1297528I-30737J24602D01*
G01X1311850D02*
G03X1291890I-9980J-3040D01*
G01X1311850D02*
G03X1318776Y1284397I37661J11473D01*
G01X1284965D02*
G03X1291890Y1297528I-30737J24602D01*
G01X1311851D02*
G03X1291890I-9980J-3040D01*
G01X1311851D02*
G03X1318775Y1284397I37663J11469D01*
G01X1377953Y3937D02*
Y51181D01*
G01Y3937D02*
Y51181D01*
G01X1370079Y3937D02*
Y55118D01*
G01X1366142Y0D02*
G03X1370079Y3937I0J3937D01*
G01X1366142Y-7874D02*
G03X1377953Y3937I0J11811D01*
G01X1346457Y-7874D02*
X1366142D01*
G01Y0D02*
G03X1370079Y3937I0J3937D01*
G01D02*
Y55118D01*
G01X1346457Y-7874D02*
X1366142D01*
G01D02*
G03X1377953Y3937I0J11811D01*
G01X1346457Y0D02*
G03Y-7874I0J-3937D01*
G01Y0D02*
G03Y-7874I0J-3937D01*
G01X1374016Y59055D02*
G03X1370079Y55118I0J-3937D01*
G01X1374016Y59056D02*
G03X1370079Y55118I0J-3937D01*
G01X1374016Y59055D02*
X1555118D01*
G01X1377953Y51181D02*
X1551181D01*
G01X1374016Y59055D02*
X1555118D01*
G01X1377953Y51181D02*
X1551181D01*
G01X1442382Y1658268D02*
G03X1450256I3937J0D01*
G01X1442382D02*
G03X1450256I3937J0D01*
G01D02*
X1919843D01*
G01X1450256D02*
X1919843D01*
G01X1562992Y0D02*
X1930906D01*
G01X1559055Y55118D02*
Y3937D01*
G01D02*
G03X1562992Y0I3937J0D01*
G01Y-7874D02*
X1593701D01*
G01X1559055Y55118D02*
Y3937D01*
G01D02*
G03X1562992Y0I3937J0D01*
G01D02*
X1930906D01*
G01X1562992Y-7874D02*
X1593701D01*
G01X1551181Y51181D02*
Y3937D01*
G01D02*
G03X1562992Y-7874I11811J0D01*
G01X1551181Y51181D02*
Y3937D01*
G01D02*
G03X1562992Y-7874I11811J0D01*
G01X1559055Y55118D02*
G03X1555118Y59055I-3937J0D01*
G01X1559055Y55118D02*
G03X1555118Y59055I-3937J0D01*
G01X1532996Y378885D02*
G03X1566807I16906J-13531D01*
G01X1532996D02*
G03X1566807I16906J-13531D01*
G01X1559882Y392016D02*
G03X1566807Y378885I37662J11471D01*
G01X1559882Y392016D02*
G03X1566807Y378885I37662J11471D01*
G01X1559882Y392016D02*
G03X1539921I-9980J-3039D01*
G01X1559882D02*
G03X1539921I-9980J-3039D01*
G01X1532996Y378885D02*
G03X1539921Y392016I-30737J24602D01*
G01X1532996Y378885D02*
G03X1539921Y392016I-30737J24602D01*
G01X1559882Y844772D02*
G03X1566807Y831641I37662J11471D01*
G01X1559882Y844772D02*
G03X1566807Y831641I37662J11471D01*
G01X1532996D02*
G03X1539921Y844772I-30737J24602D01*
G01X1532996Y831641D02*
G03X1539921Y844772I-30737J24602D01*
G01X1532996Y831641D02*
G03X1566807I16906J-13531D01*
G01X1532996D02*
G03X1566807I16906J-13531D01*
G01X1559882Y844772D02*
G03X1539921I-9980J-3040D01*
G01X1559882D02*
G03X1539921I-9980J-3039D01*
G01X1532996Y1284397D02*
G03X1566807I16906J-13531D01*
G01X1532996D02*
G03X1566807I16906J-13531D01*
G01X1559882Y1297528D02*
G03X1566807Y1284397I37662J11471D01*
G01X1559882Y1297528D02*
G03X1566807Y1284397I37662J11471D01*
G01X1559882Y1297528D02*
G03X1539921I-9980J-3040D01*
G01X1532996Y1284397D02*
G03X1539921Y1297528I-30737J24602D01*
G01X1532996Y1284397D02*
G03X1539921Y1297528I-30737J24602D01*
G01X1559882D02*
G03X1539921I-9980J-3040D01*
G01X1563976Y1382677D02*
G03Y1374803I0J-3937D01*
G01Y1382677D02*
G03Y1374803I0J-3937D01*
G01X1524606D02*
G03Y1382677I0J3937D01*
G01Y1374803D02*
G03Y1382677I0J3937D01*
G01X1864567D02*
X1563976D01*
G01X1864567D02*
X1563976D01*
G01X1593701Y-7874D02*
G03Y0I0J3937D01*
G01Y-7874D02*
G03Y0I0J3937D01*
G01X1633071D02*
G03Y-7874I0J-3937D01*
G01D02*
X1880512D01*
G01X1633071D02*
X1880512D01*
G01X1633071Y0D02*
G03Y-7874I0J-3937D01*
G01X1693996Y829921D02*
G03X1653839I-20078J0D01*
G01X1693996D02*
G03I-20079J0D01*
G01X1653839D02*
G03X1693996I20078J0D01*
G01X1781028Y378885D02*
G03X1814839I16906J-13531D01*
G01X1781028D02*
G03X1814838I16905J-13531D01*
G01X1807913Y392016D02*
G03X1814839Y378885I37662J11473D01*
G01X1807914Y392016D02*
G03X1814838Y378885I37663J11469D01*
G01X1807913Y392016D02*
G03X1787953I-9980J-3040D01*
G01X1807914D02*
G03X1787953I-9980J-3039D01*
G01X1781028Y378885D02*
G03X1787953Y392016I-30737J24602D01*
G01X1781028Y378885D02*
G03X1787953Y392016I-30737J24602D01*
G01X1807913Y844772D02*
G03X1814839Y831641I37662J11473D01*
G01X1807914Y844772D02*
G03X1814838Y831641I37663J11469D01*
G01X1781028D02*
G03X1787953Y844772I-30737J24602D01*
G01X1781028Y831641D02*
G03X1787953Y844772I-30737J24602D01*
G01X1781028Y831641D02*
G03X1814839I16906J-13531D01*
G01X1781028D02*
G03X1814838I16905J-13531D01*
G01X1807913Y844772D02*
G03X1787953I-9980J-3040D01*
G01X1807914D02*
G03X1787953I-9980J-3039D01*
G01X1781028Y1284397D02*
G03X1814839I16906J-13531D01*
G01X1781028D02*
G03X1814838I16905J-13531D01*
G01X1807913Y1297528D02*
G03X1814839Y1284397I37661J11473D01*
G01X1807914Y1297528D02*
G03X1814838Y1284397I37663J11469D01*
G01X1807913Y1297528D02*
G03X1787953I-9980J-3040D01*
G01X1781028Y1284397D02*
G03X1787953Y1297528I-30737J24602D01*
G01X1781028Y1284397D02*
G03X1787953Y1297528I-30737J24602D01*
G01X1807914D02*
G03X1787953I-9980J-3040D01*
G01X1911220Y0D02*
G03Y-7874I0J-3937D01*
G01Y0D02*
G03Y-7874I0J-3937D01*
G01X1880512D02*
G03Y0I0J3937D01*
G01Y-7874D02*
G03Y0I0J3937D01*
G01X1930906Y1382677D02*
X1895276D01*
G01D02*
G03Y1374803I0J-3937D01*
G01X1930906Y1382677D02*
X1895276D01*
G01D02*
G03Y1374803I0J-3937D01*
G01X1864567D02*
G03Y1382677I0J3937D01*
G01Y1374803D02*
G03Y1382677I0J3937D01*
G01X1919843Y-152756D02*
G03X1934843Y-137756I0J15000D01*
G01X1919843Y-152756D02*
G03X1934843Y-137756I0J15000D01*
G01Y-11811D02*
Y-137756D01*
G01Y-11811D02*
Y-137756D01*
G01X1930906Y0D02*
G03X1934843Y3937I0J3937D01*
G01X1930906Y0D02*
G03X1934843Y3937I0J3937D01*
G01Y-11811D02*
G03X1930906Y-7874I-3937J0D01*
G01X1934843Y-11811D02*
G03X1930906Y-7874I-3937J0D01*
G01X1911220D02*
X1930906D01*
G01X1911220D02*
X1930906D01*
G01X1934843Y1370866D02*
Y3937D01*
G01D02*
Y1370866D01*
G01D02*
G03X1930906Y1374803I-3937J0D01*
G01X1934843Y1370866D02*
G03X1930906Y1374803I-3937J0D01*
G01Y1382677D02*
G03X1934843Y1386614I0J3937D01*
G01X1930906Y1382677D02*
G03X1934843Y1386614I0J3937D01*
G01D02*
Y1643268D01*
G01Y1386614D02*
Y1643268D01*
G01D02*
G03X1919843Y1658268I-15000J0D01*
G01X1934843Y1643268D02*
G03X1919843Y1658268I-15000J0D01*
G54D13*
G01X459578Y113008D02*
X458571D01*
G01X459578Y114158D02*
X458571D01*
G01X459578D02*
X458571D01*
G01X459578Y113008D02*
X458571D01*
G01X462190Y115620D02*
G02X459578Y113008I-2612J0D01*
G01X461040Y115620D02*
G02X459578Y114158I-1462J0D01*
G01X462190Y124606D02*
Y115620D01*
G01X461040Y117393D02*
Y115620D01*
G01D02*
G02X459578Y114158I-1462J0D01*
G01X462190Y115620D02*
G02X459578Y113008I-2612J0D01*
G01X461040Y117393D02*
Y115620D01*
G01X462190Y124606D02*
Y115620D01*
G01Y124606D02*
Y115620D01*
G01X461039Y124978D02*
Y117394D01*
G01X463889Y126952D02*
X462190Y124606D01*
G01X463222Y127994D02*
X461039Y124978D01*
G01X463888Y126952D02*
X463889D01*
G01X495102Y134268D02*
X463222Y127994D01*
G01X495098Y133095D02*
X463888Y126952D01*
G01X495102Y134268D02*
X463222Y127994D01*
G01X526123Y126767D02*
X495098Y133095D01*
G01X526127Y127940D02*
X495102Y134268D01*
G01X461039Y124978D02*
Y117394D01*
G01X463222Y127994D02*
X461039Y124978D01*
G01X463889Y126952D02*
X462190Y124606D01*
G01X495102Y134268D02*
X463222Y127994D01*
G01X463888Y126952D02*
X463889D01*
G01X495098Y133095D02*
X463888Y126952D01*
G01X526127Y127940D02*
X495102Y134268D01*
G01X526123Y126767D02*
X495098Y133095D01*
G01X566228Y134657D02*
X526123Y126767D01*
G01X536039Y129890D02*
X526127Y127940D01*
G01X562261Y135049D02*
X536039Y129890D01*
G01D02*
X526127Y127940D01*
G01X566228Y134657D02*
X526123Y126767D01*
G01X562261Y135049D02*
X536039Y129890D01*
G01X566228Y134657D02*
X526123Y126767D01*
G01X566228Y134657D02*
X526123Y126767D01*
G01X562863Y118095D02*
X563870D01*
G01X562863Y116945D02*
X563870D01*
G01X561401Y119557D02*
G03X562863Y118095I1462J0D01*
G01X560251Y119557D02*
G03X562863Y116945I2612J0D01*
G01X561401Y124733D02*
Y119557D01*
G01X560251Y125106D02*
Y119557D01*
G01X563374Y127462D02*
X561401Y124733D01*
G01X562707Y128503D02*
X560251Y125106D01*
G01X566450Y128068D02*
X563374Y127462D01*
G01X566454Y129241D02*
X562707Y128503D01*
G01X616871Y117783D02*
X566450Y128068D01*
G01X616875Y118956D02*
X566454Y129241D01*
G01X562863Y116945D02*
X563870D01*
G01X562863Y118095D02*
X563870D01*
G01X560251Y119557D02*
G03X562863Y116945I2612J0D01*
G01X561401Y119557D02*
G03X562863Y118095I1462J0D01*
G01X560251Y125106D02*
Y119557D01*
G01X561401Y124733D02*
Y119557D01*
G01X562707Y128503D02*
X560251Y125106D01*
G01X563374Y127462D02*
X561401Y124733D01*
G01X566454Y129241D02*
X562707Y128503D01*
G01X566450Y128068D02*
X563374Y127462D01*
G01X616875Y118956D02*
X566454Y129241D01*
G01X616871Y117783D02*
X566450Y128068D01*
G01X566232Y135830D02*
X562261Y135049D01*
G01X616845Y124332D02*
X566228Y134657D01*
G01X616849Y125505D02*
X566232Y135830D01*
G01D02*
X562261Y135049D01*
G01X616849Y125505D02*
X566232Y135830D01*
G01X616845Y124332D02*
X566228Y134657D01*
G01X665280Y127305D02*
X616871Y117783D01*
G01X665284Y128478D02*
X616875Y118956D01*
G01X665284Y128478D02*
X616875Y118956D01*
G01X665280Y127305D02*
X616871Y117783D01*
G01X666221Y134047D02*
X616845Y124332D01*
G01X666225Y135220D02*
X616849Y125505D01*
G01X666225Y135220D02*
X616849Y125505D01*
G01X666221Y134047D02*
X616845Y124332D01*
G01X717309Y116694D02*
X665280Y127305D01*
G01X717313Y117867D02*
X665284Y128478D01*
G01X717313Y117867D02*
X665284Y128478D01*
G01X717309Y116694D02*
X665280Y127305D01*
G01X718148Y123456D02*
X666221Y134047D01*
G01X718152Y124629D02*
X666225Y135220D01*
G01X718152Y124629D02*
X666225Y135220D01*
G01X718148Y123456D02*
X666221Y134047D01*
G01X740214Y121203D02*
X717309Y116694D01*
G01X738839Y122105D02*
X717313Y117867D01*
G01X739774Y122289D02*
X738839Y122106D01*
G01X794587Y156517D02*
X740214Y121203D01*
G01X739774Y122289D02*
X738839Y122106D01*
G01X793755Y157348D02*
X739774Y122289D01*
G01X738839Y122105D02*
X717313Y117867D01*
G01X740214Y121203D02*
X717309Y116694D01*
G01X739774Y122289D02*
X738839Y122106D01*
G01X740214Y121203D02*
X717309Y116694D01*
G01X794587Y156517D02*
X740214Y121203D01*
G01X793755Y157348D02*
X739774Y122289D01*
G01X794587Y156517D02*
X740214Y121203D01*
G01X738365Y127435D02*
X718148Y123456D01*
G01X737925Y128521D02*
X718152Y124629D01*
G01X790133Y161053D02*
X738365Y127435D01*
G01X789297Y161882D02*
X737925Y128521D01*
G01D02*
X718152Y124629D01*
G01X738365Y127435D02*
X718148Y123456D01*
G01X789297Y161882D02*
X737925Y128521D01*
G01X790133Y161053D02*
X738365Y127435D01*
G01X921361Y352347D02*
X794587Y156517D01*
G01X920344Y352895D02*
X793755Y157348D01*
G01X920344Y352895D02*
X793755Y157348D01*
G01X921361Y352347D02*
X794587Y156517D01*
G01X914733Y356541D02*
X790133Y161053D01*
G01X804837Y186263D02*
X789297Y161882D01*
G01X804837Y186263D02*
X789297Y161882D01*
G01X914733Y356541D02*
X790133Y161053D01*
G01X914733Y356541D02*
X790133Y161053D01*
G01X914733Y356541D02*
X790133Y161053D01*
G01X914733Y356541D02*
X790133Y161053D01*
G01X914733Y356541D02*
X790133Y161053D01*
G01X914733Y356541D02*
X790133Y161053D01*
G01X914733Y356541D02*
X790133Y161053D01*
G01X914733Y356541D02*
X790133Y161053D01*
G01X914733Y356541D02*
X790133Y161053D01*
G01X820378Y210647D02*
X804837Y186263D01*
G01X888783Y317969D02*
X820379Y210647D01*
G01X820378D02*
X804837Y186263D01*
G01X888783Y317969D02*
X820379Y210647D01*
G01X839954Y625837D02*
X857162Y541284D01*
G01X838775Y625863D02*
X856069Y540886D01*
G01X838775Y625863D02*
X856069Y540886D01*
G01X839954Y625837D02*
X857162Y541284D01*
G01X861182Y710758D02*
X839954Y625837D01*
G01X860108Y711204D02*
X838775Y625863D01*
G01X860108Y711204D02*
X838775Y625863D01*
G01X861182Y710758D02*
X839954Y625837D01*
G01X891363Y322017D02*
X890314Y320372D01*
G01X903644Y341285D02*
X892894Y324420D01*
G01X891363Y322017D02*
X890314Y320372D01*
G01X903644Y341285D02*
X892894Y324420D01*
G01X892931Y475374D02*
X926645Y455299D01*
G01X892070Y474547D02*
X913799Y461609D01*
G01X857162Y541284D02*
X892931Y475374D01*
G01X856069Y540886D02*
X892070Y474547D01*
G01X892931Y475374D02*
X926645Y455299D01*
G01X892931Y475374D02*
X926645Y455299D01*
G01X892931Y475374D02*
X926645Y455299D01*
G01X892070Y474547D02*
X913799Y461609D01*
G01X892931Y475374D02*
X926645Y455299D01*
G01X856069Y540886D02*
X892070Y474547D01*
G01X857162Y541284D02*
X892931Y475374D01*
G01X886617Y534039D02*
X931561D01*
G01X886971Y532889D02*
X931084D01*
G01X886971D02*
X931084D01*
G01X886617Y534039D02*
X931561D01*
G01X1035037Y999691D02*
X861182Y710758D01*
G01X1034186Y1000508D02*
X860108Y711204D01*
G01X1034186Y1000508D02*
X860108Y711204D01*
G01X1035037Y999691D02*
X861182Y710758D01*
G01X935104Y71079D02*
X949591D01*
G01X935104Y72229D02*
X949114D01*
G01X934699Y70873D02*
G02X935104Y71079I404J-294D01*
G01X933768Y71550D02*
G02X935104Y72229I1334J-971D01*
G01X934073Y70012D02*
X934699Y70873D01*
G01X932923Y70386D02*
X933768Y71550D01*
G01X935104Y72229D02*
X949114D01*
G01X935104Y71079D02*
X949591D01*
G01X933768Y71550D02*
G02X935104Y72229I1334J-971D01*
G01X934699Y70873D02*
G02X935104Y71079I404J-294D01*
G01X932923Y70386D02*
X933768Y71550D01*
G01X934073Y70012D02*
X934699Y70873D01*
G01X968609Y370997D02*
X921361Y352347D01*
G01X968021Y372002D02*
X920495Y353242D01*
G01X968021Y372002D02*
X920495Y353242D01*
G01X968609Y370997D02*
X921361Y352347D01*
G01X906224Y345333D02*
X905176Y343689D01*
G01X908804Y349381D02*
X907756Y347736D01*
G01X911384Y353428D02*
X910336Y351784D01*
G01X913964Y357476D02*
X912916Y355832D01*
G01X964934Y376220D02*
X914733Y356541D01*
G01X917375Y358813D02*
X913964Y357476D01*
G01X906224Y345333D02*
X905176Y343689D01*
G01X908804Y349381D02*
X907756Y347736D01*
G01X911384Y353428D02*
X910336Y351784D01*
G01X913964Y357476D02*
X912916Y355832D01*
G01X917375Y358813D02*
X913964Y357476D01*
G01X964934Y376220D02*
X914733Y356541D01*
G01X964934Y376220D02*
X914733Y356541D01*
G01X964934Y376220D02*
X914733Y356541D01*
G01X964934Y376220D02*
X914733Y356541D01*
G01X964934Y376220D02*
X914733Y356541D01*
G01X964934Y376220D02*
X914733Y356541D01*
G01X964934Y376220D02*
X914733Y356541D01*
G01X964934Y376220D02*
X914733Y356541D01*
G01X921844Y360565D02*
X920028Y359853D01*
G01X926313Y362317D02*
X924497Y361605D01*
G01X946470Y370219D02*
X928966Y363357D01*
G01X921844Y360565D02*
X920028Y359853D01*
G01X926313Y362317D02*
X924497Y361605D01*
G01X946470Y370219D02*
X928966Y363357D01*
G01X934391Y449582D02*
X934073Y449145D01*
G01X933768Y450683D02*
X932923Y449519D01*
G01X934658Y449950D02*
X934391Y449582D01*
G01X933768Y450683D02*
X932923Y449519D01*
G01X934582Y452592D02*
G02X934658Y449950I-1361J-1361D01*
G01X933768Y451778D02*
G02Y450683I-548J-547D01*
G01X931874Y455299D02*
X934582Y452592D01*
G01X931397Y454149D02*
X933768Y451778D01*
G01X926328Y454149D02*
X931397D01*
G01X920373Y457695D02*
X926328Y454149D01*
G01X933768Y450683D02*
X932923Y449519D01*
G01X934391Y449582D02*
X934073Y449145D01*
G01X934658Y449950D02*
X934391Y449582D01*
G01X933768Y451778D02*
G02Y450683I-548J-547D01*
G01X934582Y452592D02*
G02X934658Y449950I-1361J-1361D01*
G01X931397Y454149D02*
X933768Y451778D01*
G01X931874Y455299D02*
X934582Y452592D01*
G01X926328Y454149D02*
X931397D01*
G01X920373Y457695D02*
X926328Y454149D01*
G01X926645Y455299D02*
X931874D01*
G01X916248Y460151D02*
X917924Y459153D01*
G01X913799Y461609D02*
X913800D01*
G01X926645Y455299D02*
X931874D01*
G01X916248Y460151D02*
X917924Y459153D01*
G01X913799Y461609D02*
X913800D01*
G01X935498Y530102D02*
X949113D01*
G01X935021Y528952D02*
X949590D01*
G01X931561Y534039D02*
X935498Y530102D01*
G01X931084Y532889D02*
X935021Y528952D01*
G01D02*
X949590D01*
G01X935498Y530102D02*
X949113D01*
G01X931084Y532889D02*
X935021Y528952D01*
G01X931561Y534039D02*
X935498Y530102D01*
G01X935104Y545850D02*
X949053D01*
G01X935104Y544700D02*
X948576D01*
G01X933768Y545171D02*
G02X935104Y545850I1334J-971D01*
G01X934699Y544494D02*
G02X935104Y544700I404J-294D01*
G01X932923Y544007D02*
X933768Y545171D01*
G01X934073Y543633D02*
X934699Y544494D01*
G01X935104Y544700D02*
X948576D01*
G01X935104Y545850D02*
X949053D01*
G01X934699Y544494D02*
G02X935104Y544700I404J-294D01*
G01X933768Y545171D02*
G02X935104Y545850I1334J-971D01*
G01X934073Y543633D02*
X934699Y544494D01*
G01X932923Y544007D02*
X933768Y545171D01*
G01X953528Y75016D02*
X1003396D01*
G01X953051Y76166D02*
X1002950D01*
G01X949591Y71079D02*
X953528Y75016D01*
G01X949114Y72229D02*
X953051Y76166D01*
G01D02*
X1002950D01*
G01X953528Y75016D02*
X1003396D01*
G01X949114Y72229D02*
X953051Y76166D01*
G01X949591Y71079D02*
X953528Y75016D01*
G01X974747Y375994D02*
X968609Y370997D01*
G01X973743Y376661D02*
X968021Y372002D01*
G01X987983Y421119D02*
X974747Y375994D01*
G01X986795Y421156D02*
X973743Y376661D01*
G01D02*
X968021Y372002D01*
G01X974747Y375994D02*
X968609Y370997D01*
G01X986795Y421156D02*
X973743Y376661D01*
G01X987983Y421119D02*
X974747Y375994D01*
G01X950939Y371971D02*
X949124Y371259D01*
G01X955408Y373722D02*
X953593Y373011D01*
G01X959877Y375474D02*
X958062Y374763D01*
G01X964346Y377226D02*
X962531Y376514D01*
G01X966903Y377826D02*
X964934Y376220D01*
G01X965901Y378493D02*
X964346Y377226D01*
G01X969220Y385650D02*
X966903Y377826D01*
G01X968032Y385689D02*
X965901Y378493D01*
G01X968576Y388497D02*
X969220Y385650D01*
G01X967559Y387778D02*
X968032Y385689D01*
G01X967622Y392712D02*
X968052Y390814D01*
G01X966498Y392459D02*
X966928Y390561D01*
G01X966561Y397393D02*
X966991Y395495D01*
G01X965438Y397140D02*
X965869Y395239D01*
G01X959043Y430571D02*
X965930Y400176D01*
G01X964377Y401822D02*
X964808Y399920D01*
G01X958024Y429860D02*
X963747Y404601D01*
G01X950939Y371971D02*
X949124Y371259D01*
G01X955408Y373722D02*
X953593Y373011D01*
G01X959877Y375474D02*
X958062Y374763D01*
G01X964346Y377226D02*
X962531Y376514D01*
G01X965901Y378493D02*
X964346Y377226D01*
G01X966903Y377826D02*
X964934Y376220D01*
G01X968032Y385689D02*
X965901Y378493D01*
G01X969220Y385650D02*
X966903Y377826D01*
G01X967559Y387778D02*
X968032Y385689D01*
G01X968576Y388497D02*
X969220Y385650D01*
G01X966498Y392459D02*
X966928Y390561D01*
G01X967622Y392712D02*
X968052Y390814D01*
G01X965438Y397140D02*
X965869Y395239D01*
G01X966561Y397393D02*
X966991Y395495D01*
G01X964377Y401822D02*
X964808Y399920D01*
G01X959043Y430571D02*
X965930Y400176D01*
G01X958024Y429860D02*
X963747Y404601D01*
G01X959043Y430571D02*
X965930Y400176D01*
G01X961154Y538972D02*
X987983Y421119D01*
G01X966209Y511585D02*
X986795Y421156D01*
G01X966209Y511585D02*
X986795Y421156D01*
G01X961154Y538972D02*
X987983Y421119D01*
G01X961154Y538972D02*
X987983Y421119D01*
G01X961154Y538972D02*
X987983Y421119D01*
G01X961154Y538972D02*
X987983Y421119D01*
G01X956056Y432544D02*
X959043Y430571D01*
G01X955710Y431394D02*
X958023Y429866D01*
G01X953352Y432544D02*
X956056D01*
G01X953829Y431394D02*
X955710D01*
G01X949765Y428957D02*
X953352Y432544D01*
G01X950579Y428144D02*
X953829Y431394D01*
G01X949685Y426201D02*
G02X949764Y428957I1500J1336D01*
G01X950579Y426930D02*
G02Y428144I607J607D01*
G01X950179Y425522D02*
X949685Y426201D01*
G01X951329Y425897D02*
X950579Y426930D01*
G01X955710Y431394D02*
X958023Y429866D01*
G01X956056Y432544D02*
X959043Y430571D01*
G01X953829Y431394D02*
X955710D01*
G01X953352Y432544D02*
X956056D01*
G01X950579Y428144D02*
X953829Y431394D01*
G01X949765Y428957D02*
X953352Y432544D01*
G01X950579Y426930D02*
G02Y428144I607J607D01*
G01X949685Y426201D02*
G02X949764Y428957I1500J1336D01*
G01X951329Y425897D02*
X950579Y426930D01*
G01X950179Y425522D02*
X949685Y426201D01*
G01X951484Y533568D02*
X950639Y534732D01*
G01X952107Y534669D02*
X951789Y535106D01*
G01X952374Y534301D02*
X952107Y534669D01*
G01X951484Y532473D02*
G03Y533568I-547J548D01*
G01X952298Y531659D02*
G03X952374Y534301I-1361J1361D01*
G01X949113Y530102D02*
X951484Y532473D01*
G01X950858Y530220D02*
X952298Y531659D01*
G01X949590Y528952D02*
X950858Y530220D01*
G01X952107Y534669D02*
X951789Y535106D01*
G01X951484Y533568D02*
X950639Y534732D01*
G01X952374Y534301D02*
X952107Y534669D01*
G01X951484Y533568D02*
X950639Y534732D01*
G01X952298Y531659D02*
G03X952374Y534301I-1361J1361D01*
G01X951484Y532473D02*
G03Y533568I-547J548D01*
G01X950858Y530220D02*
X952298Y531659D01*
G01X949113Y530102D02*
X951484Y532473D01*
G01X949590Y528952D02*
X950858Y530220D01*
G01X949113Y530102D02*
X951484Y532473D01*
G01X965126Y516343D02*
X965559Y514442D01*
G01X964043Y521101D02*
X964475Y519200D01*
G01X960106Y538393D02*
X963392Y523958D01*
G01X958213Y541913D02*
X961154Y538972D01*
G01X957736Y540763D02*
X960106Y538393D01*
G01X952990Y541913D02*
X958213D01*
G01X952513Y540763D02*
X957736D01*
G01X949053Y545850D02*
X952990Y541913D01*
G01X948576Y544700D02*
X952513Y540763D01*
G01X965126Y516343D02*
X965559Y514442D01*
G01X964043Y521101D02*
X964475Y519200D01*
G01X960106Y538393D02*
X963392Y523958D01*
G01X957736Y540763D02*
X960106Y538393D01*
G01X958213Y541913D02*
X961154Y538972D01*
G01X952513Y540763D02*
X957736D01*
G01X952990Y541913D02*
X958213D01*
G01X948576Y544700D02*
X952513Y540763D01*
G01X949053Y545850D02*
X952990Y541913D01*
G01X1061150Y1016884D02*
X1035037Y999691D01*
G01X1086921Y1035229D02*
X1034186Y1000508D01*
G01X1086921Y1035229D02*
X1034186Y1000508D01*
G01X1086921Y1035229D02*
X1034186Y1000508D01*
G01X1086921Y1035229D02*
X1034186Y1000508D01*
G01X1061150Y1016884D02*
X1035037Y999691D01*
G01X1074606Y67142D02*
X1099542D01*
G01X1074606D02*
X1099542D01*
G01X1074208Y68292D02*
X1099542D01*
G01X1074208D02*
X1099542D01*
G01X1072046Y535354D02*
X1054594D01*
G01X1071569Y534204D02*
X1054594D01*
G01X1073361Y534039D02*
X1072046Y535354D01*
G01X1072884Y532889D02*
X1071569Y534204D01*
G01X1099388Y534039D02*
X1073361D01*
G01X1098911Y532889D02*
X1072884D01*
G01X1071569Y534204D02*
X1054594D01*
G01X1072046Y535354D02*
X1054594D01*
G01X1072884Y532889D02*
X1071569Y534204D01*
G01X1073361Y534039D02*
X1072046Y535354D01*
G01X1098911Y532889D02*
X1072884D01*
G01X1099388Y534039D02*
X1073361D01*
G01X1084756Y1032426D02*
X1061150Y1016884D01*
G01X1087266Y1034079D02*
X1084756Y1032426D01*
G01X1114925Y1034079D02*
X1087266D01*
G01X1084756Y1032426D02*
X1061150Y1016884D01*
G01X1087266Y1034079D02*
X1084756Y1032426D01*
G01X1114925Y1034079D02*
X1087266D01*
G01X1114925Y1035229D02*
X1086921D01*
G01X1114925D02*
X1086921D01*
G01X1099542Y67142D02*
G03X1100878Y67821I2J1650D01*
G01X1099542Y67142D02*
G03X1100878Y67821I2J1650D01*
G01X1099947Y68498D02*
X1100573Y69359D01*
G01X1100878Y67821D02*
X1101723Y68985D01*
G01X1099542Y68292D02*
G03X1099947Y68498I1J500D01*
G01X1100878Y67821D02*
X1101723Y68985D01*
G01X1099947Y68498D02*
X1100573Y69359D01*
G01X1099542Y68292D02*
G03X1099947Y68498I1J500D01*
G01X1119594Y423332D02*
X1118749Y424496D01*
G01X1120525Y424009D02*
X1119899Y424870D01*
G01X1120930Y422653D02*
G02X1119594Y423332I-2J1650D01*
G01X1120930Y423803D02*
G02X1120525Y424009I-1J500D01*
G01X1124852Y422653D02*
X1120930D01*
G01X1125212Y423803D02*
X1120930D01*
G01X1137705Y413743D02*
X1124852Y422653D01*
G01X1139290Y414045D02*
X1125212Y423803D01*
G01X1139290Y414045D02*
X1125212Y423803D01*
G01X1139290Y414045D02*
X1125212Y423803D01*
G01X1139290Y414045D02*
X1125212Y423803D01*
G01X1120525Y424009D02*
X1119899Y424870D01*
G01X1119594Y423332D02*
X1118749Y424496D01*
G01X1120930Y423803D02*
G02X1120525Y424009I-1J500D01*
G01X1120930Y422653D02*
G02X1119594Y423332I-2J1650D01*
G01X1125212Y423803D02*
X1120930D01*
G01X1124852Y422653D02*
X1120930D01*
G01X1139290Y414045D02*
X1125212Y423803D01*
G01X1137705Y413743D02*
X1124852Y422653D01*
G01X1102434Y543980D02*
X1102183Y543634D01*
G01X1101502Y544654D02*
X1101033Y544007D01*
G01X1101554Y544726D02*
X1101504Y544657D01*
G01X1102488Y544053D02*
X1102436Y543981D01*
G01X1101502Y544654D02*
X1101033Y544007D01*
G01X1101861Y545150D02*
X1101557Y544730D01*
G01X1102793Y544475D02*
X1102490Y544056D01*
G01X1101554Y544726D02*
X1101504Y544657D01*
G01X1101861Y545150D02*
X1101557Y544730D01*
G01X1103233Y544700D02*
G03X1102793Y544475I1J-544D01*
G01X1103233Y545850D02*
G03X1101861Y545150I0J-1695D01*
G01X1116862Y544700D02*
X1103233D01*
G01X1117339Y545850D02*
X1103233D01*
G01X1120799Y540763D02*
X1116862Y544700D01*
G01X1121276Y541913D02*
X1117339Y545850D01*
G01X1126787Y540763D02*
X1120799D01*
G01X1127147Y541913D02*
X1121276D01*
G01X1133116Y536375D02*
X1126787Y540763D01*
G01X1133933Y537209D02*
X1127147Y541913D01*
G01X1134260Y534796D02*
X1133116Y536375D01*
G01X1172665Y483719D02*
X1133933Y537209D01*
G01X1137028Y530973D02*
X1135884Y532552D01*
G01X1172665Y483719D02*
X1133933Y537209D01*
G01X1172665Y483719D02*
X1133933Y537209D01*
G01X1172665Y483719D02*
X1133933Y537209D01*
G01X1172665Y483719D02*
X1133933Y537209D01*
G01X1101502Y544654D02*
X1101033Y544007D01*
G01X1102434Y543980D02*
X1102183Y543634D01*
G01X1102488Y544053D02*
X1102436Y543981D01*
G01X1101554Y544726D02*
X1101504Y544657D01*
G01X1102434Y543980D02*
X1102183Y543634D01*
G01X1102793Y544475D02*
X1102490Y544056D01*
G01X1101861Y545150D02*
X1101557Y544730D01*
G01X1102488Y544053D02*
X1102436Y543981D01*
G01X1102793Y544475D02*
X1102490Y544056D01*
G01X1103233Y545850D02*
G03X1101861Y545150I0J-1695D01*
G01X1103233Y544700D02*
G03X1102793Y544475I1J-544D01*
G01X1117339Y545850D02*
X1103233D01*
G01X1116862Y544700D02*
X1103233D01*
G01X1121276Y541913D02*
X1117339Y545850D01*
G01X1120799Y540763D02*
X1116862Y544700D01*
G01X1127147Y541913D02*
X1121276D01*
G01X1126787Y540763D02*
X1120799D01*
G01X1133933Y537209D02*
X1127147Y541913D01*
G01X1133116Y536375D02*
X1126787Y540763D01*
G01X1172665Y483719D02*
X1133933Y537209D01*
G01X1134260Y534796D02*
X1133116Y536375D01*
G01X1137028Y530973D02*
X1135884Y532552D01*
G01X1103325Y530102D02*
X1099388Y534039D01*
G01X1102848Y528952D02*
X1098911Y532889D01*
G01X1117223Y530102D02*
X1103325D01*
G01X1117700Y528952D02*
X1102848D01*
G01X1119594Y532473D02*
X1117223Y530102D01*
G01X1118968Y530220D02*
X1117700Y528952D01*
G01X1120408Y531659D02*
X1118968Y530220D01*
G01X1119594Y533568D02*
G02Y532473I-548J-547D01*
G01X1120484Y534301D02*
G02X1120408Y531659I-1437J-1281D01*
G01X1118749Y534732D02*
X1119594Y533568D01*
G01X1120217Y534669D02*
X1120484Y534301D01*
G01X1119899Y535106D02*
X1120217Y534669D01*
G01X1102848Y528952D02*
X1098911Y532889D01*
G01X1103325Y530102D02*
X1099388Y534039D01*
G01X1117700Y528952D02*
X1102848D01*
G01X1117223Y530102D02*
X1103325D01*
G01X1118968Y530220D02*
X1117700Y528952D01*
G01X1119594Y532473D02*
X1117223Y530102D01*
G01X1120408Y531659D02*
X1118968Y530220D01*
G01X1119594Y532473D02*
X1117223Y530102D01*
G01X1120484Y534301D02*
G02X1120408Y531659I-1437J-1281D01*
G01X1119594Y533568D02*
G02Y532473I-548J-547D01*
G01X1120217Y534669D02*
X1120484Y534301D01*
G01X1118749Y534732D02*
X1119594Y533568D01*
G01X1119899Y535106D02*
X1120217Y534669D01*
G01X1118749Y534732D02*
X1119594Y533568D01*
G01X1116861Y1036015D02*
G02X1114925Y1034079I-1936J0D01*
G01X1116861Y1036015D02*
G02X1114925Y1034079I-1936J0D01*
G01X1115711Y1036015D02*
G02X1114925Y1035229I-786J0D01*
G01X1116861Y1037698D02*
Y1036015D01*
G01X1115711Y1037698D02*
Y1036015D01*
G01D02*
G02X1114925Y1035229I-786J0D01*
G01X1115711Y1037698D02*
Y1036015D01*
G01X1116861Y1037698D02*
Y1036015D01*
G01X1200326Y327786D02*
X1138474Y413211D01*
G01X1201396Y328270D02*
X1159185Y386569D01*
G01X1200326Y327786D02*
X1138474Y413211D01*
G01X1200326Y327786D02*
X1138474Y413211D01*
G01X1200326Y327786D02*
X1138474Y413211D01*
G01X1200326Y327786D02*
X1138474Y413211D01*
G01X1201396Y328270D02*
X1159185Y386569D01*
G01X1200326Y327786D02*
X1138474Y413211D01*
G01X1149068Y400541D02*
X1139290Y414045D01*
G01X1151883Y396653D02*
X1150740Y398232D01*
G01X1154698Y392765D02*
X1153555Y394344D01*
G01X1157513Y388877D02*
X1156370Y390456D01*
G01X1149068Y400541D02*
X1139290Y414045D01*
G01X1151883Y396653D02*
X1150740Y398232D01*
G01X1154698Y392765D02*
X1153555Y394344D01*
G01X1157513Y388877D02*
X1156370Y390456D01*
G01X1213365Y298878D02*
X1171595Y483235D01*
G01X1214540Y298898D02*
X1172666Y483713D01*
G01X1214540Y298898D02*
X1172666Y483713D01*
G01X1213365Y298878D02*
X1171595Y483235D01*
G01X1137725Y413729D02*
X1137705Y413743D01*
G01X1138089Y413476D02*
X1137725Y413729D01*
G01X1138474Y413211D02*
X1138089Y413476D01*
G01X1137725Y413729D02*
X1137705Y413743D01*
G01X1138089Y413476D02*
X1137725Y413729D01*
G01X1138474Y413211D02*
X1138089Y413476D01*
G01X1171595Y483235D02*
X1144189Y521083D01*
G01X1171595Y483235D02*
X1144189Y521083D01*
G01X1139796Y527150D02*
X1138653Y528729D01*
G01X1142565Y523327D02*
X1141421Y524906D01*
G01X1139796Y527150D02*
X1138653Y528729D01*
G01X1142565Y523327D02*
X1141421Y524906D01*
G01X1215496Y208236D02*
X1205572Y252019D01*
G01X1214418Y207786D02*
X1206931Y240819D01*
G01X1215496Y208236D02*
X1205572Y252019D01*
G01X1236394Y173291D02*
X1214418Y207786D01*
G01X1259231Y139584D02*
X1215496Y208236D01*
G01X1259231Y139584D02*
X1215496Y208236D01*
G01X1259231Y139584D02*
X1215496Y208236D01*
G01D02*
X1205572Y252019D01*
G01X1214418Y207786D02*
X1206931Y240819D01*
G01X1259231Y139584D02*
X1215496Y208236D01*
G01X1236394Y173291D02*
X1214418Y207786D01*
G01X1209174Y206042D02*
X1199010Y250891D01*
G01X1208096Y205593D02*
X1202970Y228212D01*
G01X1209174Y206042D02*
X1199010Y250891D01*
G01X1254064Y133395D02*
X1208096Y205593D01*
G01X1254885Y134247D02*
X1209174Y206042D01*
G01D02*
X1199010Y250891D01*
G01X1208096Y205593D02*
X1202970Y228212D01*
G01X1254885Y134247D02*
X1209174Y206042D01*
G01X1254064Y133395D02*
X1208096Y205593D01*
G01X1204397Y251999D02*
X1213365Y298878D01*
G01X1205572Y252019D02*
X1214540Y298898D01*
G01X1206931Y240819D02*
X1204397Y251999D01*
G01X1205572Y252019D02*
X1214540Y298898D01*
G01X1204397Y251999D02*
X1213365Y298878D01*
G01X1206931Y240819D02*
X1204397Y251999D01*
G01X1199010Y250891D02*
X1208128Y298555D01*
G01X1199010Y250891D02*
X1208128Y298555D01*
G01X1197835Y250871D02*
X1200912Y266956D01*
G01X1199010Y250891D02*
X1208128Y298555D01*
G01X1202970Y228212D02*
X1197835Y250871D01*
G01X1199010Y250891D02*
X1208128Y298555D01*
G01X1197835Y250871D02*
X1200912Y266956D01*
G01X1202970Y228212D02*
X1197835Y250871D01*
G01X1206953Y298535D02*
X1200326Y327786D01*
G01X1208128Y298555D02*
X1201396Y328270D01*
G01X1203943Y282804D02*
X1206953Y298535D01*
G01X1200912Y266956D02*
X1203943Y282804D01*
G01X1208128Y298555D02*
X1201396Y328270D01*
G01X1206953Y298535D02*
X1200326Y327786D01*
G01X1203943Y282804D02*
X1206953Y298535D01*
G01X1200912Y266956D02*
X1203943Y282804D01*
G01X1247328Y156127D02*
X1236394Y173291D01*
G01X1258400Y138747D02*
X1247328Y156127D01*
G01X1268333Y132517D02*
X1258400Y138747D01*
G01X1268664Y133667D02*
X1259231Y139584D01*
G01X1296309Y132517D02*
X1268333D01*
G01X1295741Y133667D02*
X1268664D01*
G01X1247328Y156127D02*
X1236394Y173291D01*
G01X1258400Y138747D02*
X1247328Y156127D01*
G01X1268664Y133667D02*
X1259231Y139584D01*
G01X1268333Y132517D02*
X1258400Y138747D01*
G01X1295741Y133667D02*
X1268664D01*
G01X1296309Y132517D02*
X1268333D01*
G01X1266353Y126199D02*
X1254064Y133395D01*
G01X1266665Y127349D02*
X1254885Y134247D01*
G01X1299663Y126199D02*
X1266353D01*
G01X1299094Y127349D02*
X1266665D01*
G01D02*
X1254885Y134247D01*
G01X1266353Y126199D02*
X1254064Y133395D01*
G01X1299094Y127349D02*
X1266665D01*
G01X1299663Y126199D02*
X1266353D01*
G01X1307448Y147054D02*
X1296309Y132517D01*
G01X1306727Y148004D02*
X1295741Y133667D01*
G01X1325466Y154284D02*
X1307448Y147054D01*
G01X1325344Y155475D02*
X1306727Y148004D01*
G01X1334725Y152627D02*
X1325466Y154284D01*
G01X1339557Y152932D02*
X1325344Y155475D01*
G01X1306727Y148004D02*
X1295741Y133667D01*
G01X1307448Y147054D02*
X1296309Y132517D01*
G01X1325344Y155475D02*
X1306727Y148004D01*
G01X1325466Y154284D02*
X1307448Y147054D01*
G01X1339557Y152932D02*
X1325344Y155475D01*
G01X1334725Y152627D02*
X1325466Y154284D01*
G01X1311306Y141415D02*
X1299663Y126199D01*
G01X1310578Y142356D02*
X1299094Y127349D01*
G01X1324957Y147184D02*
X1311306Y141415D01*
G01X1324806Y148369D02*
X1310578Y142356D01*
G01X1333151Y145975D02*
X1324957Y147184D01*
G01X1341642Y145885D02*
X1324806Y148369D01*
G01X1341642Y145885D02*
X1324806Y148369D01*
G01X1310578Y142356D02*
X1299094Y127349D01*
G01X1311306Y141415D02*
X1299663Y126199D01*
G01X1324806Y148369D02*
X1310578Y142356D01*
G01X1324957Y147184D02*
X1311306Y141415D01*
G01X1341642Y145885D02*
X1324806Y148369D01*
G01X1333151Y145975D02*
X1324957Y147184D01*
G01X1343985Y150970D02*
X1334725Y152627D01*
G01X1344301Y152082D02*
X1339558Y152931D01*
G01X1393499Y131355D02*
X1343985Y150970D01*
G01X1393719Y132505D02*
X1344301Y152082D01*
G01D02*
X1339558Y152931D01*
G01X1343985Y150970D02*
X1334725Y152627D01*
G01X1393719Y132505D02*
X1344301Y152082D01*
G01X1393499Y131355D02*
X1343985Y150970D01*
G01X1341342Y144766D02*
X1333151Y145975D01*
G01X1390865Y125143D02*
X1341342Y144766D01*
G01X1391085Y126293D02*
X1341642Y145885D01*
G01X1341342Y144766D02*
X1333151Y145975D01*
G01X1391085Y126293D02*
X1341642Y145885D01*
G01X1390865Y125143D02*
X1341342Y144766D01*
G01X1422456Y115620D02*
Y122335D01*
G01X1423606Y115620D02*
Y122812D01*
G01X1425068Y113008D02*
G02X1422456Y115620I0J2612D01*
G01X1425068Y114158D02*
G02X1423606Y115620I0J1462D01*
G01X1426075Y113008D02*
X1425068D01*
G01X1426075Y114158D02*
X1425068D01*
G01X1423606Y115620D02*
Y122812D01*
G01X1422456Y115620D02*
Y122335D01*
G01X1425068Y114158D02*
G02X1423606Y115620I0J1462D01*
G01X1425068Y113008D02*
G02X1422456Y115620I0J2612D01*
G01X1426075Y114158D02*
X1425068D01*
G01X1426075Y113008D02*
X1425068D01*
G01X1521070Y131355D02*
X1393499D01*
G01X1521547Y132505D02*
X1393719D01*
G01X1521547D02*
X1393719D01*
G01X1521070Y131355D02*
X1393499D01*
G01X1419648Y125143D02*
X1390865D01*
G01X1420125Y126293D02*
X1391085D01*
G01X1422456Y122335D02*
X1419648Y125143D01*
G01X1423606Y122812D02*
X1420125Y126293D01*
G01D02*
X1391085D01*
G01X1419648Y125143D02*
X1390865D01*
G01X1423606Y122812D02*
X1420125Y126293D01*
G01X1422456Y122335D02*
X1419648Y125143D01*
G01X1528755Y123670D02*
X1521070Y131355D01*
G01X1529905Y124147D02*
X1521547Y132505D01*
G01X1529905Y124147D02*
X1521547Y132505D01*
G01X1528755Y123670D02*
X1521070Y131355D01*
G01X1528755Y119557D02*
Y123670D01*
G01X1529905Y119557D02*
Y124147D01*
G01X1531367Y116945D02*
G02X1528755Y119557I0J2612D01*
G01X1531367Y118095D02*
G02X1529905Y119557I0J1462D01*
G01X1532374Y116945D02*
X1531367D01*
G01X1532374Y118095D02*
X1531367D01*
G01X1529905Y119557D02*
Y124147D01*
G01X1528755Y119557D02*
Y123670D01*
G01X1531367Y118095D02*
G02X1529905Y119557I0J1462D01*
G01X1531367Y116945D02*
G02X1528755Y119557I0J2612D01*
G01X1532374Y118095D02*
X1531367D01*
G01X1532374Y116945D02*
X1531367D01*
M02*
